(kicad_sch
	(version 20250114)
	(generator "eeschema")
	(generator_version "9.0")
	(paper "A3")
	(title_block
		(title "Kintex 410T devboard")
		(date "2024-04-03")
		(rev "1.1.2")
	)
	(text "DDR3L"
		(exclude_from_sim no)
		(at 14.605 18.415 0)
		(effects
			(font
				(size 1.27 1.27)
				(thickness 0.4)
				(bold yes)
			)
			(justify left bottom)
		)
	)
	(text "VTT DECOUPLING"
		(exclude_from_sim no)
		(at 320.675 41.91 0)
		(effects
			(font
				(size 1.27 1.27)
			)
			(justify left bottom)
		)
	)
	(text "Termination"
		(exclude_from_sim no)
		(at 169.545 223.52 0)
		(effects
			(font
				(size 1.27 1.27)
			)
			(justify left bottom)
		)
	)
	(text "SRAM"
		(exclude_from_sim no)
		(at 15.24 158.115 0)
		(effects
			(font
				(size 1.27 1.27)
				(thickness 0.4)
				(bold yes)
			)
			(justify left bottom)
		)
	)
	(text "Termination"
		(exclude_from_sim no)
		(at 189.23 79.375 0)
		(effects
			(font
				(size 1.27 1.27)
			)
			(justify left bottom)
		)
	)
	(junction
		(at 224.79 87.63)
		(diameter 0)
		(color 0 0 0 0)
	)
	(junction
		(at 325.12 109.22)
		(diameter 0)
		(color 0 0 0 0)
	)
	(junction
		(at 377.19 92.71)
		(diameter 0)
		(color 0 0 0 0)
	)
	(junction
		(at 146.05 184.15)
		(diameter 0)
		(color 0 0 0 0)
	)
	(junction
		(at 90.17 121.92)
		(diameter 0)
		(color 0 0 0 0)
	)
	(junction
		(at 320.04 60.96)
		(diameter 0)
		(color 0 0 0 0)
	)
	(junction
		(at 377.19 90.17)
		(diameter 0)
		(color 0 0 0 0)
	)
	(junction
		(at 274.32 95.25)
		(diameter 0)
		(color 0 0 0 0)
	)
	(junction
		(at 377.19 106.68)
		(diameter 0)
		(color 0 0 0 0)
	)
	(junction
		(at 325.12 95.25)
		(diameter 0)
		(color 0 0 0 0)
	)
	(junction
		(at 170.18 25.4)
		(diameter 0)
		(color 0 0 0 0)
	)
	(junction
		(at 307.34 25.4)
		(diameter 0)
		(color 0 0 0 0)
	)
	(junction
		(at 351.79 52.07)
		(diameter 0)
		(color 0 0 0 0)
	)
	(junction
		(at 196.85 25.4)
		(diameter 0)
		(color 0 0 0 0)
	)
	(junction
		(at 153.67 257.81)
		(diameter 0)
		(color 0 0 0 0)
	)
	(junction
		(at 274.32 104.14)
		(diameter 0)
		(color 0 0 0 0)
	)
	(junction
		(at 204.47 232.41)
		(diameter 0)
		(color 0 0 0 0)
	)
	(junction
		(at 334.01 60.96)
		(diameter 0)
		(color 0 0 0 0)
	)
	(junction
		(at 191.77 121.92)
		(diameter 0)
		(color 0 0 0 0)
	)
	(junction
		(at 311.15 52.07)
		(diameter 0)
		(color 0 0 0 0)
	)
	(junction
		(at 257.81 25.4)
		(diameter 0)
		(color 0 0 0 0)
	)
	(junction
		(at 377.19 109.22)
		(diameter 0)
		(color 0 0 0 0)
	)
	(junction
		(at 311.15 60.96)
		(diameter 0)
		(color 0 0 0 0)
	)
	(junction
		(at 334.01 43.18)
		(diameter 0)
		(color 0 0 0 0)
	)
	(junction
		(at 234.95 121.92)
		(diameter 0)
		(color 0 0 0 0)
	)
	(junction
		(at 377.19 87.63)
		(diameter 0)
		(color 0 0 0 0)
	)
	(junction
		(at 165.1 121.92)
		(diameter 0)
		(color 0 0 0 0)
	)
	(junction
		(at 107.95 48.26)
		(diameter 0)
		(color 0 0 0 0)
	)
	(junction
		(at 325.12 92.71)
		(diameter 0)
		(color 0 0 0 0)
	)
	(junction
		(at 274.32 90.17)
		(diameter 0)
		(color 0 0 0 0)
	)
	(junction
		(at 285.75 121.92)
		(diameter 0)
		(color 0 0 0 0)
	)
	(junction
		(at 320.04 52.07)
		(diameter 0)
		(color 0 0 0 0)
	)
	(junction
		(at 311.15 43.18)
		(diameter 0)
		(color 0 0 0 0)
	)
	(junction
		(at 95.25 257.81)
		(diameter 0)
		(color 0 0 0 0)
	)
	(junction
		(at 214.63 25.4)
		(diameter 0)
		(color 0 0 0 0)
	)
	(junction
		(at 342.9 52.07)
		(diameter 0)
		(color 0 0 0 0)
	)
	(junction
		(at 274.32 87.63)
		(diameter 0)
		(color 0 0 0 0)
	)
	(junction
		(at 320.04 43.18)
		(diameter 0)
		(color 0 0 0 0)
	)
	(junction
		(at 275.59 25.4)
		(diameter 0)
		(color 0 0 0 0)
	)
	(junction
		(at 204.47 234.95)
		(diameter 0)
		(color 0 0 0 0)
	)
	(junction
		(at 232.41 25.4)
		(diameter 0)
		(color 0 0 0 0)
	)
	(junction
		(at 274.32 109.22)
		(diameter 0)
		(color 0 0 0 0)
	)
	(junction
		(at 168.91 184.15)
		(diameter 0)
		(color 0 0 0 0)
	)
	(junction
		(at 377.19 104.14)
		(diameter 0)
		(color 0 0 0 0)
	)
	(junction
		(at 274.32 106.68)
		(diameter 0)
		(color 0 0 0 0)
	)
	(junction
		(at 377.19 95.25)
		(diameter 0)
		(color 0 0 0 0)
	)
	(junction
		(at 266.7 25.4)
		(diameter 0)
		(color 0 0 0 0)
	)
	(junction
		(at 325.12 104.14)
		(diameter 0)
		(color 0 0 0 0)
	)
	(junction
		(at 325.12 87.63)
		(diameter 0)
		(color 0 0 0 0)
	)
	(junction
		(at 223.52 25.4)
		(diameter 0)
		(color 0 0 0 0)
	)
	(junction
		(at 196.85 53.34)
		(diameter 0)
		(color 0 0 0 0)
	)
	(junction
		(at 325.12 106.68)
		(diameter 0)
		(color 0 0 0 0)
	)
	(junction
		(at 204.47 229.87)
		(diameter 0)
		(color 0 0 0 0)
	)
	(junction
		(at 342.9 60.96)
		(diameter 0)
		(color 0 0 0 0)
	)
	(junction
		(at 154.94 184.15)
		(diameter 0)
		(color 0 0 0 0)
	)
	(junction
		(at 241.3 25.4)
		(diameter 0)
		(color 0 0 0 0)
	)
	(junction
		(at 146.05 53.34)
		(diameter 0)
		(color 0 0 0 0)
	)
	(junction
		(at 146.05 48.26)
		(diameter 0)
		(color 0 0 0 0)
	)
	(junction
		(at 147.32 111.76)
		(diameter 0)
		(color 0 0 0 0)
	)
	(junction
		(at 179.07 25.4)
		(diameter 0)
		(color 0 0 0 0)
	)
	(junction
		(at 342.9 43.18)
		(diameter 0)
		(color 0 0 0 0)
	)
	(junction
		(at 187.96 25.4)
		(diameter 0)
		(color 0 0 0 0)
	)
	(junction
		(at 334.01 52.07)
		(diameter 0)
		(color 0 0 0 0)
	)
	(junction
		(at 161.29 25.4)
		(diameter 0)
		(color 0 0 0 0)
	)
	(junction
		(at 205.74 25.4)
		(diameter 0)
		(color 0 0 0 0)
	)
	(junction
		(at 274.32 92.71)
		(diameter 0)
		(color 0 0 0 0)
	)
	(junction
		(at 325.12 90.17)
		(diameter 0)
		(color 0 0 0 0)
	)
	(junction
		(at 187.96 53.34)
		(diameter 0)
		(color 0 0 0 0)
	)
	(junction
		(at 152.4 25.4)
		(diameter 0)
		(color 0 0 0 0)
	)
	(junction
		(at 250.19 25.4)
		(diameter 0)
		(color 0 0 0 0)
	)
	(no_connect
		(at 142.24 88.9)
	)
	(bus_entry
		(at 96.52 222.25)
		(size -1.27 1.27)
		(stroke
			(width 0)
			(type default)
		)
	)
	(bus_entry
		(at 163.83 63.5)
		(size 1.27 1.27)
		(stroke
			(width 0)
			(type default)
		)
	)
	(bus_entry
		(at 236.22 109.22)
		(size -1.27 1.27)
		(stroke
			(width 0)
			(type default)
		)
	)
	(bus_entry
		(at 152.4 237.49)
		(size 1.27 1.27)
		(stroke
			(width 0)
			(type default)
		)
	)
	(bus_entry
		(at 152.4 229.87)
		(size 1.27 1.27)
		(stroke
			(width 0)
			(type default)
		)
	)
	(bus_entry
		(at 163.83 60.96)
		(size 1.27 1.27)
		(stroke
			(width 0)
			(type default)
		)
	)
	(bus_entry
		(at 96.52 247.65)
		(size -1.27 1.27)
		(stroke
			(width 0)
			(type default)
		)
	)
	(bus_entry
		(at 91.44 48.26)
		(size -1.27 1.27)
		(stroke
			(width 0)
			(type default)
		)
	)
	(bus_entry
		(at 337.82 92.71)
		(size -1.27 1.27)
		(stroke
			(width 0)
			(type default)
		)
	)
	(bus_entry
		(at 96.52 201.93)
		(size -1.27 1.27)
		(stroke
			(width 0)
			(type default)
		)
	)
	(bus_entry
		(at 337.82 111.76)
		(size -1.27 1.27)
		(stroke
			(width 0)
			(type default)
		)
	)
	(bus_entry
		(at 91.44 55.88)
		(size -1.27 1.27)
		(stroke
			(width 0)
			(type default)
		)
	)
	(bus_entry
		(at 96.52 217.17)
		(size -1.27 1.27)
		(stroke
			(width 0)
			(type default)
		)
	)
	(bus_entry
		(at 91.44 101.6)
		(size -1.27 1.27)
		(stroke
			(width 0)
			(type default)
		)
	)
	(bus_entry
		(at 91.44 86.36)
		(size -1.27 1.27)
		(stroke
			(width 0)
			(type default)
		)
	)
	(bus_entry
		(at 91.44 76.2)
		(size -1.27 1.27)
		(stroke
			(width 0)
			(type default)
		)
	)
	(bus_entry
		(at 287.02 95.25)
		(size -1.27 1.27)
		(stroke
			(width 0)
			(type default)
		)
	)
	(bus_entry
		(at 91.44 60.96)
		(size -1.27 1.27)
		(stroke
			(width 0)
			(type default)
		)
	)
	(bus_entry
		(at 96.52 227.33)
		(size -1.27 1.27)
		(stroke
			(width 0)
			(type default)
		)
	)
	(bus_entry
		(at 96.52 212.09)
		(size -1.27 1.27)
		(stroke
			(width 0)
			(type default)
		)
	)
	(bus_entry
		(at 96.52 219.71)
		(size -1.27 1.27)
		(stroke
			(width 0)
			(type default)
		)
	)
	(bus_entry
		(at 337.82 95.25)
		(size -1.27 1.27)
		(stroke
			(width 0)
			(type default)
		)
	)
	(bus_entry
		(at 91.44 91.44)
		(size -1.27 1.27)
		(stroke
			(width 0)
			(type default)
		)
	)
	(bus_entry
		(at 236.22 90.17)
		(size -1.27 1.27)
		(stroke
			(width 0)
			(type default)
		)
	)
	(bus_entry
		(at 163.83 68.58)
		(size 1.27 1.27)
		(stroke
			(width 0)
			(type default)
		)
	)
	(bus_entry
		(at 91.44 53.34)
		(size -1.27 1.27)
		(stroke
			(width 0)
			(type default)
		)
	)
	(bus_entry
		(at 152.4 224.79)
		(size 1.27 1.27)
		(stroke
			(width 0)
			(type default)
		)
	)
	(bus_entry
		(at 287.02 104.14)
		(size -1.27 1.27)
		(stroke
			(width 0)
			(type default)
		)
	)
	(bus_entry
		(at 91.44 81.28)
		(size -1.27 1.27)
		(stroke
			(width 0)
			(type default)
		)
	)
	(bus_entry
		(at 91.44 96.52)
		(size -1.27 1.27)
		(stroke
			(width 0)
			(type default)
		)
	)
	(bus_entry
		(at 152.4 234.95)
		(size 1.27 1.27)
		(stroke
			(width 0)
			(type default)
		)
	)
	(bus_entry
		(at 96.52 242.57)
		(size -1.27 1.27)
		(stroke
			(width 0)
			(type default)
		)
	)
	(bus_entry
		(at 163.83 78.74)
		(size 1.27 1.27)
		(stroke
			(width 0)
			(type default)
		)
	)
	(bus_entry
		(at 287.02 106.68)
		(size -1.27 1.27)
		(stroke
			(width 0)
			(type default)
		)
	)
	(bus_entry
		(at 236.22 111.76)
		(size -1.27 1.27)
		(stroke
			(width 0)
			(type default)
		)
	)
	(bus_entry
		(at 96.52 240.03)
		(size -1.27 1.27)
		(stroke
			(width 0)
			(type default)
		)
	)
	(bus_entry
		(at 236.22 106.68)
		(size -1.27 1.27)
		(stroke
			(width 0)
			(type default)
		)
	)
	(bus_entry
		(at 96.52 234.95)
		(size -1.27 1.27)
		(stroke
			(width 0)
			(type default)
		)
	)
	(bus_entry
		(at 172.72 237.49)
		(size -1.27 1.27)
		(stroke
			(width 0)
			(type default)
		)
	)
	(bus_entry
		(at 152.4 222.25)
		(size 1.27 1.27)
		(stroke
			(width 0)
			(type default)
		)
	)
	(bus_entry
		(at 96.52 229.87)
		(size -1.27 1.27)
		(stroke
			(width 0)
			(type default)
		)
	)
	(bus_entry
		(at 172.72 229.87)
		(size -1.27 1.27)
		(stroke
			(width 0)
			(type default)
		)
	)
	(bus_entry
		(at 163.83 99.06)
		(size 1.27 1.27)
		(stroke
			(width 0)
			(type default)
		)
	)
	(bus_entry
		(at 236.22 104.14)
		(size -1.27 1.27)
		(stroke
			(width 0)
			(type default)
		)
	)
	(bus_entry
		(at 236.22 87.63)
		(size -1.27 1.27)
		(stroke
			(width 0)
			(type default)
		)
	)
	(bus_entry
		(at 91.44 73.66)
		(size -1.27 1.27)
		(stroke
			(width 0)
			(type default)
		)
	)
	(bus_entry
		(at 152.4 207.01)
		(size 1.27 1.27)
		(stroke
			(width 0)
			(type default)
		)
	)
	(bus_entry
		(at 91.44 83.82)
		(size -1.27 1.27)
		(stroke
			(width 0)
			(type default)
		)
	)
	(bus_entry
		(at 91.44 93.98)
		(size -1.27 1.27)
		(stroke
			(width 0)
			(type default)
		)
	)
	(bus_entry
		(at 152.4 217.17)
		(size 1.27 1.27)
		(stroke
			(width 0)
			(type default)
		)
	)
	(bus_entry
		(at 96.52 237.49)
		(size -1.27 1.27)
		(stroke
			(width 0)
			(type default)
		)
	)
	(bus_entry
		(at 193.04 104.14)
		(size -1.27 1.27)
		(stroke
			(width 0)
			(type default)
		)
	)
	(bus_entry
		(at 337.82 104.14)
		(size -1.27 1.27)
		(stroke
			(width 0)
			(type default)
		)
	)
	(bus_entry
		(at 287.02 87.63)
		(size -1.27 1.27)
		(stroke
			(width 0)
			(type default)
		)
	)
	(bus_entry
		(at 96.52 209.55)
		(size -1.27 1.27)
		(stroke
			(width 0)
			(type default)
		)
	)
	(bus_entry
		(at 172.72 232.41)
		(size -1.27 1.27)
		(stroke
			(width 0)
			(type default)
		)
	)
	(bus_entry
		(at 163.83 86.36)
		(size 1.27 1.27)
		(stroke
			(width 0)
			(type default)
		)
	)
	(bus_entry
		(at 172.72 234.95)
		(size -1.27 1.27)
		(stroke
			(width 0)
			(type default)
		)
	)
	(bus_entry
		(at 163.83 71.12)
		(size 1.27 1.27)
		(stroke
			(width 0)
			(type default)
		)
	)
	(bus_entry
		(at 91.44 63.5)
		(size -1.27 1.27)
		(stroke
			(width 0)
			(type default)
		)
	)
	(bus_entry
		(at 96.52 232.41)
		(size -1.27 1.27)
		(stroke
			(width 0)
			(type default)
		)
	)
	(bus_entry
		(at 163.83 83.82)
		(size 1.27 1.27)
		(stroke
			(width 0)
			(type default)
		)
	)
	(bus_entry
		(at 152.4 232.41)
		(size 1.27 1.27)
		(stroke
			(width 0)
			(type default)
		)
	)
	(bus_entry
		(at 96.52 245.11)
		(size -1.27 1.27)
		(stroke
			(width 0)
			(type default)
		)
	)
	(bus_entry
		(at 91.44 78.74)
		(size -1.27 1.27)
		(stroke
			(width 0)
			(type default)
		)
	)
	(bus_entry
		(at 193.04 87.63)
		(size -1.27 1.27)
		(stroke
			(width 0)
			(type default)
		)
	)
	(bus_entry
		(at 193.04 91.44)
		(size -1.27 1.27)
		(stroke
			(width 0)
			(type default)
		)
	)
	(bus_entry
		(at 193.04 101.6)
		(size -1.27 1.27)
		(stroke
			(width 0)
			(type default)
		)
	)
	(bus_entry
		(at 91.44 88.9)
		(size -1.27 1.27)
		(stroke
			(width 0)
			(type default)
		)
	)
	(bus_entry
		(at 337.82 109.22)
		(size -1.27 1.27)
		(stroke
			(width 0)
			(type default)
		)
	)
	(bus_entry
		(at 287.02 111.76)
		(size -1.27 1.27)
		(stroke
			(width 0)
			(type default)
		)
	)
	(bus_entry
		(at 152.4 209.55)
		(size 1.27 1.27)
		(stroke
			(width 0)
			(type default)
		)
	)
	(bus_entry
		(at 152.4 212.09)
		(size 1.27 1.27)
		(stroke
			(width 0)
			(type default)
		)
	)
	(bus_entry
		(at 91.44 106.68)
		(size -1.27 1.27)
		(stroke
			(width 0)
			(type default)
		)
	)
	(bus_entry
		(at 287.02 109.22)
		(size -1.27 1.27)
		(stroke
			(width 0)
			(type default)
		)
	)
	(bus_entry
		(at 152.4 219.71)
		(size 1.27 1.27)
		(stroke
			(width 0)
			(type default)
		)
	)
	(bus_entry
		(at 91.44 71.12)
		(size -1.27 1.27)
		(stroke
			(width 0)
			(type default)
		)
	)
	(bus_entry
		(at 91.44 50.8)
		(size -1.27 1.27)
		(stroke
			(width 0)
			(type default)
		)
	)
	(bus_entry
		(at 91.44 111.76)
		(size -1.27 1.27)
		(stroke
			(width 0)
			(type default)
		)
	)
	(bus_entry
		(at 163.83 93.98)
		(size 1.27 1.27)
		(stroke
			(width 0)
			(type default)
		)
	)
	(bus_entry
		(at 287.02 90.17)
		(size -1.27 1.27)
		(stroke
			(width 0)
			(type default)
		)
	)
	(bus_entry
		(at 152.4 214.63)
		(size 1.27 1.27)
		(stroke
			(width 0)
			(type default)
		)
	)
	(bus_entry
		(at 287.02 92.71)
		(size -1.27 1.27)
		(stroke
			(width 0)
			(type default)
		)
	)
	(bus_entry
		(at 91.44 66.04)
		(size -1.27 1.27)
		(stroke
			(width 0)
			(type default)
		)
	)
	(bus_entry
		(at 337.82 87.63)
		(size -1.27 1.27)
		(stroke
			(width 0)
			(type default)
		)
	)
	(bus_entry
		(at 96.52 207.01)
		(size -1.27 1.27)
		(stroke
			(width 0)
			(type default)
		)
	)
	(bus_entry
		(at 236.22 92.71)
		(size -1.27 1.27)
		(stroke
			(width 0)
			(type default)
		)
	)
	(bus_entry
		(at 163.83 96.52)
		(size 1.27 1.27)
		(stroke
			(width 0)
			(type default)
		)
	)
	(bus_entry
		(at 163.83 66.04)
		(size 1.27 1.27)
		(stroke
			(width 0)
			(type default)
		)
	)
	(bus_entry
		(at 96.52 224.79)
		(size -1.27 1.27)
		(stroke
			(width 0)
			(type default)
		)
	)
	(bus_entry
		(at 91.44 104.14)
		(size -1.27 1.27)
		(stroke
			(width 0)
			(type default)
		)
	)
	(bus_entry
		(at 163.83 73.66)
		(size 1.27 1.27)
		(stroke
			(width 0)
			(type default)
		)
	)
	(bus_entry
		(at 163.83 81.28)
		(size 1.27 1.27)
		(stroke
			(width 0)
			(type default)
		)
	)
	(bus_entry
		(at 163.83 76.2)
		(size 1.27 1.27)
		(stroke
			(width 0)
			(type default)
		)
	)
	(bus_entry
		(at 337.82 106.68)
		(size -1.27 1.27)
		(stroke
			(width 0)
			(type default)
		)
	)
	(bus_entry
		(at 163.83 101.6)
		(size 1.27 1.27)
		(stroke
			(width 0)
			(type default)
		)
	)
	(bus_entry
		(at 96.52 214.63)
		(size -1.27 1.27)
		(stroke
			(width 0)
			(type default)
		)
	)
	(bus_entry
		(at 96.52 199.39)
		(size -1.27 1.27)
		(stroke
			(width 0)
			(type default)
		)
	)
	(bus_entry
		(at 96.52 204.47)
		(size -1.27 1.27)
		(stroke
			(width 0)
			(type default)
		)
	)
	(bus_entry
		(at 236.22 95.25)
		(size -1.27 1.27)
		(stroke
			(width 0)
			(type default)
		)
	)
	(bus_entry
		(at 91.44 68.58)
		(size -1.27 1.27)
		(stroke
			(width 0)
			(type default)
		)
	)
	(bus_entry
		(at 91.44 58.42)
		(size -1.27 1.27)
		(stroke
			(width 0)
			(type default)
		)
	)
	(bus_entry
		(at 337.82 90.17)
		(size -1.27 1.27)
		(stroke
			(width 0)
			(type default)
		)
	)
	(wire
		(pts
			(xy 91.44 96.52) (xy 111.76 96.52)
		)
		(stroke
			(width 0)
			(type default)
		)
	)
	(wire
		(pts
			(xy 359.41 87.63) (xy 337.82 87.63)
		)
		(stroke
			(width 0)
			(type default)
		)
	)
	(wire
		(pts
			(xy 142.24 93.98) (xy 163.83 93.98)
		)
		(stroke
			(width 0)
			(type default)
		)
	)
	(wire
		(pts
			(xy 224.79 104.14) (xy 218.44 104.14)
		)
		(stroke
			(width 0)
			(type default)
		)
	)
	(bus
		(pts
			(xy 234.95 105.41) (xy 234.95 107.95)
		)
		(stroke
			(width 0)
			(type default)
		)
	)
	(bus
		(pts
			(xy 95.25 241.3) (xy 95.25 243.84)
		)
		(stroke
			(width 0)
			(type default)
		)
	)
	(bus
		(pts
			(xy 165.1 77.47) (xy 165.1 80.01)
		)
		(stroke
			(width 0)
			(type default)
		)
	)
	(wire
		(pts
			(xy 359.41 106.68) (xy 337.82 106.68)
		)
		(stroke
			(width 0)
			(type default)
		)
	)
	(wire
		(pts
			(xy 161.29 25.4) (xy 161.29 27.94)
		)
		(stroke
			(width 0)
			(type default)
		)
	)
	(wire
		(pts
			(xy 152.4 234.95) (xy 137.16 234.95)
		)
		(stroke
			(width 0)
			(type default)
		)
	)
	(wire
		(pts
			(xy 187.96 53.34) (xy 187.96 55.88)
		)
		(stroke
			(width 0)
			(type default)
		)
	)
	(bus
		(pts
			(xy 90.17 69.85) (xy 90.17 72.39)
		)
		(stroke
			(width 0)
			(type default)
		)
	)
	(wire
		(pts
			(xy 96.52 219.71) (xy 111.76 219.71)
		)
		(stroke
			(width 0)
			(type default)
		)
	)
	(wire
		(pts
			(xy 274.32 90.17) (xy 274.32 92.71)
		)
		(stroke
			(width 0)
			(type default)
		)
	)
	(wire
		(pts
			(xy 311.15 50.8) (xy 311.15 52.07)
		)
		(stroke
			(width 0)
			(type default)
		)
	)
	(wire
		(pts
			(xy 139.7 199.39) (xy 139.7 184.15)
		)
		(stroke
			(width 0)
			(type default)
		)
	)
	(wire
		(pts
			(xy 267.97 106.68) (xy 274.32 106.68)
		)
		(stroke
			(width 0)
			(type default)
		)
	)
	(wire
		(pts
			(xy 325.12 90.17) (xy 325.12 92.71)
		)
		(stroke
			(width 0)
			(type default)
		)
	)
	(wire
		(pts
			(xy 142.24 48.26) (xy 146.05 48.26)
		)
		(stroke
			(width 0)
			(type default)
		)
	)
	(wire
		(pts
			(xy 236.22 92.71) (xy 257.81 92.71)
		)
		(stroke
			(width 0)
			(type default)
		)
	)
	(wire
		(pts
			(xy 204.47 229.87) (xy 204.47 232.41)
		)
		(stroke
			(width 0)
			(type default)
		)
	)
	(polyline
		(pts
			(xy 361.95 38.1) (xy 293.37 38.1)
		)
		(stroke
			(width 0)
			(type default)
		)
	)
	(wire
		(pts
			(xy 137.16 199.39) (xy 139.7 199.39)
		)
		(stroke
			(width 0)
			(type default)
		)
	)
	(wire
		(pts
			(xy 369.57 95.25) (xy 377.19 95.25)
		)
		(stroke
			(width 0)
			(type default)
		)
	)
	(bus
		(pts
			(xy 95.25 215.9) (xy 95.25 218.44)
		)
		(stroke
			(width 0)
			(type default)
		)
	)
	(wire
		(pts
			(xy 196.85 60.96) (xy 196.85 63.5)
		)
		(stroke
			(width 0)
			(type default)
		)
	)
	(bus
		(pts
			(xy 285.75 93.98) (xy 285.75 96.52)
		)
		(stroke
			(width 0)
			(type default)
		)
	)
	(wire
		(pts
			(xy 172.72 229.87) (xy 190.5 229.87)
		)
		(stroke
			(width 0)
			(type default)
		)
	)
	(bus
		(pts
			(xy 234.95 107.95) (xy 234.95 110.49)
		)
		(stroke
			(width 0)
			(type default)
		)
	)
	(wire
		(pts
			(xy 334.01 50.8) (xy 334.01 52.07)
		)
		(stroke
			(width 0)
			(type default)
		)
	)
	(wire
		(pts
			(xy 193.04 87.63) (xy 213.36 87.63)
		)
		(stroke
			(width 0)
			(type default)
		)
	)
	(wire
		(pts
			(xy 91.44 63.5) (xy 111.76 63.5)
		)
		(stroke
			(width 0)
			(type default)
		)
	)
	(bus
		(pts
			(xy 95.25 213.36) (xy 95.25 215.9)
		)
		(stroke
			(width 0)
			(type default)
		)
	)
	(wire
		(pts
			(xy 142.24 60.96) (xy 163.83 60.96)
		)
		(stroke
			(width 0)
			(type default)
		)
	)
	(wire
		(pts
			(xy 107.95 30.48) (xy 100.33 30.48)
		)
		(stroke
			(width 0)
			(type default)
		)
	)
	(wire
		(pts
			(xy 223.52 33.02) (xy 223.52 35.56)
		)
		(stroke
			(width 0)
			(type default)
		)
	)
	(wire
		(pts
			(xy 154.94 184.15) (xy 168.91 184.15)
		)
		(stroke
			(width 0)
			(type default)
		)
	)
	(bus
		(pts
			(xy 95.25 203.2) (xy 95.25 205.74)
		)
		(stroke
			(width 0)
			(type default)
		)
	)
	(bus
		(pts
			(xy 336.55 113.03) (xy 336.55 120.65)
		)
		(stroke
			(width 0)
			(type default)
		)
	)
	(bus
		(pts
			(xy 90.17 62.23) (xy 90.17 64.77)
		)
		(stroke
			(width 0)
			(type default)
		)
	)
	(wire
		(pts
			(xy 307.34 25.4) (xy 307.34 24.13)
		)
		(stroke
			(width 0)
			(type default)
		)
	)
	(bus
		(pts
			(xy 90.17 113.03) (xy 90.17 121.92)
		)
		(stroke
			(width 0)
			(type default)
		)
	)
	(wire
		(pts
			(xy 236.22 95.25) (xy 257.81 95.25)
		)
		(stroke
			(width 0)
			(type default)
		)
	)
	(bus
		(pts
			(xy 336.55 88.9) (xy 336.55 91.44)
		)
		(stroke
			(width 0)
			(type default)
		)
	)
	(wire
		(pts
			(xy 200.66 237.49) (xy 204.47 237.49)
		)
		(stroke
			(width 0)
			(type default)
		)
	)
	(wire
		(pts
			(xy 351.79 43.18) (xy 351.79 45.72)
		)
		(stroke
			(width 0)
			(type default)
		)
	)
	(bus
		(pts
			(xy 95.25 226.06) (xy 95.25 228.6)
		)
		(stroke
			(width 0)
			(type default)
		)
	)
	(wire
		(pts
			(xy 91.44 68.58) (xy 111.76 68.58)
		)
		(stroke
			(width 0)
			(type default)
		)
	)
	(bus
		(pts
			(xy 165.1 97.79) (xy 165.1 100.33)
		)
		(stroke
			(width 0)
			(type default)
		)
	)
	(wire
		(pts
			(xy 359.41 92.71) (xy 337.82 92.71)
		)
		(stroke
			(width 0)
			(type default)
		)
	)
	(wire
		(pts
			(xy 377.19 106.68) (xy 377.19 109.22)
		)
		(stroke
			(width 0)
			(type default)
		)
	)
	(wire
		(pts
			(xy 267.97 90.17) (xy 274.32 90.17)
		)
		(stroke
			(width 0)
			(type default)
		)
	)
	(bus
		(pts
			(xy 78.74 257.81) (xy 95.25 257.81)
		)
		(stroke
			(width 0)
			(type default)
		)
	)
	(wire
		(pts
			(xy 342.9 43.18) (xy 342.9 45.72)
		)
		(stroke
			(width 0)
			(type default)
		)
	)
	(wire
		(pts
			(xy 311.15 52.07) (xy 311.15 54.61)
		)
		(stroke
			(width 0)
			(type default)
		)
	)
	(wire
		(pts
			(xy 200.66 232.41) (xy 204.47 232.41)
		)
		(stroke
			(width 0)
			(type default)
		)
	)
	(wire
		(pts
			(xy 96.52 247.65) (xy 111.76 247.65)
		)
		(stroke
			(width 0)
			(type default)
		)
	)
	(wire
		(pts
			(xy 96.52 209.55) (xy 111.76 209.55)
		)
		(stroke
			(width 0)
			(type default)
		)
	)
	(wire
		(pts
			(xy 142.24 73.66) (xy 163.83 73.66)
		)
		(stroke
			(width 0)
			(type default)
		)
	)
	(wire
		(pts
			(xy 377.19 95.25) (xy 377.19 104.14)
		)
		(stroke
			(width 0)
			(type default)
		)
	)
	(wire
		(pts
			(xy 187.96 33.02) (xy 187.96 35.56)
		)
		(stroke
			(width 0)
			(type default)
		)
	)
	(bus
		(pts
			(xy 95.25 257.81) (xy 153.67 257.81)
		)
		(stroke
			(width 0)
			(type default)
		)
	)
	(wire
		(pts
			(xy 152.4 214.63) (xy 137.16 214.63)
		)
		(stroke
			(width 0)
			(type default)
		)
	)
	(wire
		(pts
			(xy 267.97 111.76) (xy 274.32 111.76)
		)
		(stroke
			(width 0)
			(type default)
		)
	)
	(wire
		(pts
			(xy 152.4 232.41) (xy 137.16 232.41)
		)
		(stroke
			(width 0)
			(type default)
		)
	)
	(wire
		(pts
			(xy 232.41 25.4) (xy 232.41 27.94)
		)
		(stroke
			(width 0)
			(type default)
		)
	)
	(polyline
		(pts
			(xy 383.54 127) (xy 187.96 127)
		)
		(stroke
			(width 0)
			(type default)
		)
	)
	(wire
		(pts
			(xy 91.44 88.9) (xy 111.76 88.9)
		)
		(stroke
			(width 0)
			(type default)
		)
	)
	(wire
		(pts
			(xy 147.32 111.76) (xy 147.32 114.3)
		)
		(stroke
			(width 0)
			(type default)
		)
	)
	(wire
		(pts
			(xy 96.52 229.87) (xy 111.76 229.87)
		)
		(stroke
			(width 0)
			(type default)
		)
	)
	(polyline
		(pts
			(xy 383.54 76.2) (xy 383.54 127)
		)
		(stroke
			(width 0)
			(type default)
		)
	)
	(wire
		(pts
			(xy 369.57 87.63) (xy 377.19 87.63)
		)
		(stroke
			(width 0)
			(type default)
		)
	)
	(bus
		(pts
			(xy 90.17 52.07) (xy 90.17 54.61)
		)
		(stroke
			(width 0)
			(type default)
		)
	)
	(bus
		(pts
			(xy 336.55 91.44) (xy 336.55 93.98)
		)
		(stroke
			(width 0)
			(type default)
		)
	)
	(wire
		(pts
			(xy 91.44 53.34) (xy 111.76 53.34)
		)
		(stroke
			(width 0)
			(type default)
		)
	)
	(wire
		(pts
			(xy 91.44 91.44) (xy 111.76 91.44)
		)
		(stroke
			(width 0)
			(type default)
		)
	)
	(wire
		(pts
			(xy 342.9 50.8) (xy 342.9 52.07)
		)
		(stroke
			(width 0)
			(type default)
		)
	)
	(wire
		(pts
			(xy 214.63 25.4) (xy 214.63 27.94)
		)
		(stroke
			(width 0)
			(type default)
		)
	)
	(wire
		(pts
			(xy 204.47 232.41) (xy 204.47 234.95)
		)
		(stroke
			(width 0)
			(type default)
		)
	)
	(bus
		(pts
			(xy 165.1 121.92) (xy 191.77 121.92)
		)
		(stroke
			(width 0)
			(type default)
		)
	)
	(wire
		(pts
			(xy 142.24 111.76) (xy 147.32 111.76)
		)
		(stroke
			(width 0)
			(type default)
		)
	)
	(wire
		(pts
			(xy 342.9 59.69) (xy 342.9 60.96)
		)
		(stroke
			(width 0)
			(type default)
		)
	)
	(wire
		(pts
			(xy 96.52 224.79) (xy 111.76 224.79)
		)
		(stroke
			(width 0)
			(type default)
		)
	)
	(wire
		(pts
			(xy 96.52 237.49) (xy 111.76 237.49)
		)
		(stroke
			(width 0)
			(type default)
		)
	)
	(bus
		(pts
			(xy 153.67 210.82) (xy 153.67 213.36)
		)
		(stroke
			(width 0)
			(type default)
		)
	)
	(bus
		(pts
			(xy 285.75 88.9) (xy 285.75 91.44)
		)
		(stroke
			(width 0)
			(type default)
		)
	)
	(wire
		(pts
			(xy 142.24 50.8) (xy 146.05 50.8)
		)
		(stroke
			(width 0)
			(type default)
		)
	)
	(bus
		(pts
			(xy 191.77 102.87) (xy 191.77 105.41)
		)
		(stroke
			(width 0)
			(type default)
		)
	)
	(bus
		(pts
			(xy 165.1 87.63) (xy 165.1 95.25)
		)
		(stroke
			(width 0)
			(type default)
		)
	)
	(wire
		(pts
			(xy 154.94 184.15) (xy 154.94 186.69)
		)
		(stroke
			(width 0)
			(type default)
		)
	)
	(wire
		(pts
			(xy 96.52 204.47) (xy 111.76 204.47)
		)
		(stroke
			(width 0)
			(type default)
		)
	)
	(wire
		(pts
			(xy 257.81 25.4) (xy 266.7 25.4)
		)
		(stroke
			(width 0)
			(type default)
		)
	)
	(bus
		(pts
			(xy 95.25 238.76) (xy 95.25 241.3)
		)
		(stroke
			(width 0)
			(type default)
		)
	)
	(bus
		(pts
			(xy 78.74 121.92) (xy 90.17 121.92)
		)
		(stroke
			(width 0)
			(type default)
		)
	)
	(wire
		(pts
			(xy 318.77 90.17) (xy 325.12 90.17)
		)
		(stroke
			(width 0)
			(type default)
		)
	)
	(wire
		(pts
			(xy 140.97 245.11) (xy 140.97 250.19)
		)
		(stroke
			(width 0)
			(type default)
		)
	)
	(wire
		(pts
			(xy 308.61 87.63) (xy 287.02 87.63)
		)
		(stroke
			(width 0)
			(type default)
		)
	)
	(wire
		(pts
			(xy 142.24 81.28) (xy 163.83 81.28)
		)
		(stroke
			(width 0)
			(type default)
		)
	)
	(wire
		(pts
			(xy 334.01 52.07) (xy 334.01 54.61)
		)
		(stroke
			(width 0)
			(type default)
		)
	)
	(wire
		(pts
			(xy 142.24 63.5) (xy 163.83 63.5)
		)
		(stroke
			(width 0)
			(type default)
		)
	)
	(wire
		(pts
			(xy 152.4 224.79) (xy 137.16 224.79)
		)
		(stroke
			(width 0)
			(type default)
		)
	)
	(wire
		(pts
			(xy 311.15 43.18) (xy 311.15 45.72)
		)
		(stroke
			(width 0)
			(type default)
		)
	)
	(bus
		(pts
			(xy 165.1 67.31) (xy 165.1 69.85)
		)
		(stroke
			(width 0)
			(type default)
		)
	)
	(wire
		(pts
			(xy 152.4 207.01) (xy 137.16 207.01)
		)
		(stroke
			(width 0)
			(type default)
		)
	)
	(wire
		(pts
			(xy 318.77 92.71) (xy 325.12 92.71)
		)
		(stroke
			(width 0)
			(type default)
		)
	)
	(wire
		(pts
			(xy 179.07 25.4) (xy 179.07 27.94)
		)
		(stroke
			(width 0)
			(type default)
		)
	)
	(wire
		(pts
			(xy 300.99 50.8) (xy 300.99 52.07)
		)
		(stroke
			(width 0)
			(type default)
		)
	)
	(wire
		(pts
			(xy 351.79 52.07) (xy 351.79 54.61)
		)
		(stroke
			(width 0)
			(type default)
		)
	)
	(bus
		(pts
			(xy 153.67 215.9) (xy 153.67 218.44)
		)
		(stroke
			(width 0)
			(type default)
		)
	)
	(wire
		(pts
			(xy 196.85 33.02) (xy 196.85 35.56)
		)
		(stroke
			(width 0)
			(type default)
		)
	)
	(bus
		(pts
			(xy 191.77 88.9) (xy 191.77 92.71)
		)
		(stroke
			(width 0)
			(type default)
		)
	)
	(bus
		(pts
			(xy 336.55 105.41) (xy 336.55 107.95)
		)
		(stroke
			(width 0)
			(type default)
		)
	)
	(wire
		(pts
			(xy 96.52 217.17) (xy 111.76 217.17)
		)
		(stroke
			(width 0)
			(type default)
		)
	)
	(bus
		(pts
			(xy 285.75 121.92) (xy 335.28 121.92)
		)
		(stroke
			(width 0)
			(type default)
		)
	)
	(wire
		(pts
			(xy 96.52 234.95) (xy 111.76 234.95)
		)
		(stroke
			(width 0)
			(type default)
		)
	)
	(wire
		(pts
			(xy 168.91 191.77) (xy 168.91 193.04)
		)
		(stroke
			(width 0)
			(type default)
		)
	)
	(wire
		(pts
			(xy 369.57 90.17) (xy 377.19 90.17)
		)
		(stroke
			(width 0)
			(type default)
		)
	)
	(wire
		(pts
			(xy 142.24 71.12) (xy 163.83 71.12)
		)
		(stroke
			(width 0)
			(type default)
		)
	)
	(wire
		(pts
			(xy 308.61 109.22) (xy 287.02 109.22)
		)
		(stroke
			(width 0)
			(type default)
		)
	)
	(bus
		(pts
			(xy 165.1 74.93) (xy 165.1 77.47)
		)
		(stroke
			(width 0)
			(type default)
		)
	)
	(wire
		(pts
			(xy 318.77 87.63) (xy 325.12 87.63)
		)
		(stroke
			(width 0)
			(type default)
		)
	)
	(wire
		(pts
			(xy 196.85 25.4) (xy 205.74 25.4)
		)
		(stroke
			(width 0)
			(type default)
		)
	)
	(bus
		(pts
			(xy 285.75 91.44) (xy 285.75 93.98)
		)
		(stroke
			(width 0)
			(type default)
		)
	)
	(wire
		(pts
			(xy 359.41 90.17) (xy 337.82 90.17)
		)
		(stroke
			(width 0)
			(type default)
		)
	)
	(polyline
		(pts
			(xy 187.96 76.2) (xy 187.96 127)
		)
		(stroke
			(width 0)
			(type default)
		)
	)
	(wire
		(pts
			(xy 311.15 52.07) (xy 320.04 52.07)
		)
		(stroke
			(width 0)
			(type default)
		)
	)
	(wire
		(pts
			(xy 334.01 59.69) (xy 334.01 60.96)
		)
		(stroke
			(width 0)
			(type default)
		)
	)
	(wire
		(pts
			(xy 224.79 101.6) (xy 193.04 101.6)
		)
		(stroke
			(width 0)
			(type default)
		)
	)
	(wire
		(pts
			(xy 320.04 50.8) (xy 320.04 52.07)
		)
		(stroke
			(width 0)
			(type default)
		)
	)
	(bus
		(pts
			(xy 153.67 213.36) (xy 153.67 215.9)
		)
		(stroke
			(width 0)
			(type default)
		)
	)
	(wire
		(pts
			(xy 142.24 109.22) (xy 147.32 109.22)
		)
		(stroke
			(width 0)
			(type default)
		)
	)
	(wire
		(pts
			(xy 168.91 184.15) (xy 168.91 186.69)
		)
		(stroke
			(width 0)
			(type default)
		)
	)
	(wire
		(pts
			(xy 311.15 25.4) (xy 311.15 43.18)
		)
		(stroke
			(width 0)
			(type default)
		)
	)
	(bus
		(pts
			(xy 234.95 88.9) (xy 234.95 91.44)
		)
		(stroke
			(width 0)
			(type default)
		)
	)
	(wire
		(pts
			(xy 236.22 90.17) (xy 257.81 90.17)
		)
		(stroke
			(width 0)
			(type default)
		)
	)
	(wire
		(pts
			(xy 369.57 109.22) (xy 377.19 109.22)
		)
		(stroke
			(width 0)
			(type default)
		)
	)
	(wire
		(pts
			(xy 377.19 104.14) (xy 377.19 106.68)
		)
		(stroke
			(width 0)
			(type default)
		)
	)
	(wire
		(pts
			(xy 156.21 104.14) (xy 156.21 107.95)
		)
		(stroke
			(width 0)
			(type default)
		)
	)
	(wire
		(pts
			(xy 142.24 99.06) (xy 163.83 99.06)
		)
		(stroke
			(width 0)
			(type default)
		)
	)
	(wire
		(pts
			(xy 187.96 53.34) (xy 196.85 53.34)
		)
		(stroke
			(width 0)
			(type default)
		)
	)
	(wire
		(pts
			(xy 308.61 92.71) (xy 287.02 92.71)
		)
		(stroke
			(width 0)
			(type default)
		)
	)
	(wire
		(pts
			(xy 320.04 52.07) (xy 334.01 52.07)
		)
		(stroke
			(width 0)
			(type default)
		)
	)
	(wire
		(pts
			(xy 377.19 92.71) (xy 377.19 95.25)
		)
		(stroke
			(width 0)
			(type default)
		)
	)
	(wire
		(pts
			(xy 187.96 25.4) (xy 187.96 27.94)
		)
		(stroke
			(width 0)
			(type default)
		)
	)
	(wire
		(pts
			(xy 170.18 25.4) (xy 170.18 27.94)
		)
		(stroke
			(width 0)
			(type default)
		)
	)
	(wire
		(pts
			(xy 325.12 95.25) (xy 325.12 104.14)
		)
		(stroke
			(width 0)
			(type default)
		)
	)
	(wire
		(pts
			(xy 224.79 87.63) (xy 224.79 91.44)
		)
		(stroke
			(width 0)
			(type default)
		)
	)
	(wire
		(pts
			(xy 96.52 222.25) (xy 111.76 222.25)
		)
		(stroke
			(width 0)
			(type default)
		)
	)
	(bus
		(pts
			(xy 165.1 80.01) (xy 165.1 82.55)
		)
		(stroke
			(width 0)
			(type default)
		)
	)
	(wire
		(pts
			(xy 152.4 222.25) (xy 137.16 222.25)
		)
		(stroke
			(width 0)
			(type default)
		)
	)
	(wire
		(pts
			(xy 142.24 68.58) (xy 163.83 68.58)
		)
		(stroke
			(width 0)
			(type default)
		)
	)
	(wire
		(pts
			(xy 342.9 43.18) (xy 351.79 43.18)
		)
		(stroke
			(width 0)
			(type default)
		)
	)
	(bus
		(pts
			(xy 90.17 105.41) (xy 90.17 107.95)
		)
		(stroke
			(width 0)
			(type default)
		)
	)
	(bus
		(pts
			(xy 95.25 218.44) (xy 95.25 220.98)
		)
		(stroke
			(width 0)
			(type default)
		)
	)
	(wire
		(pts
			(xy 172.72 234.95) (xy 190.5 234.95)
		)
		(stroke
			(width 0)
			(type default)
		)
	)
	(bus
		(pts
			(xy 90.17 64.77) (xy 90.17 67.31)
		)
		(stroke
			(width 0)
			(type default)
		)
	)
	(bus
		(pts
			(xy 153.67 226.06) (xy 153.67 231.14)
		)
		(stroke
			(width 0)
			(type default)
		)
	)
	(bus
		(pts
			(xy 90.17 95.25) (xy 90.17 97.79)
		)
		(stroke
			(width 0)
			(type default)
		)
	)
	(wire
		(pts
			(xy 152.4 217.17) (xy 137.16 217.17)
		)
		(stroke
			(width 0)
			(type default)
		)
	)
	(bus
		(pts
			(xy 90.17 57.15) (xy 90.17 59.69)
		)
		(stroke
			(width 0)
			(type default)
		)
	)
	(bus
		(pts
			(xy 90.17 80.01) (xy 90.17 82.55)
		)
		(stroke
			(width 0)
			(type default)
		)
	)
	(polyline
		(pts
			(xy 13.97 146.05) (xy 406.4 146.05)
		)
		(stroke
			(width 0)
			(type default)
		)
	)
	(wire
		(pts
			(xy 91.44 60.96) (xy 111.76 60.96)
		)
		(stroke
			(width 0)
			(type default)
		)
	)
	(wire
		(pts
			(xy 318.77 106.68) (xy 325.12 106.68)
		)
		(stroke
			(width 0)
			(type default)
		)
	)
	(bus
		(pts
			(xy 95.25 208.28) (xy 95.25 210.82)
		)
		(stroke
			(width 0)
			(type default)
		)
	)
	(wire
		(pts
			(xy 236.22 87.63) (xy 257.81 87.63)
		)
		(stroke
			(width 0)
			(type default)
		)
	)
	(wire
		(pts
			(xy 257.81 106.68) (xy 236.22 106.68)
		)
		(stroke
			(width 0)
			(type default)
		)
	)
	(bus
		(pts
			(xy 153.67 233.68) (xy 153.67 236.22)
		)
		(stroke
			(width 0)
			(type default)
		)
	)
	(wire
		(pts
			(xy 377.19 90.17) (xy 377.19 92.71)
		)
		(stroke
			(width 0)
			(type default)
		)
	)
	(wire
		(pts
			(xy 308.61 111.76) (xy 287.02 111.76)
		)
		(stroke
			(width 0)
			(type default)
		)
	)
	(wire
		(pts
			(xy 96.52 199.39) (xy 111.76 199.39)
		)
		(stroke
			(width 0)
			(type default)
		)
	)
	(wire
		(pts
			(xy 257.81 111.76) (xy 236.22 111.76)
		)
		(stroke
			(width 0)
			(type default)
		)
	)
	(polyline
		(pts
			(xy 168.91 220.98) (xy 168.91 260.35)
		)
		(stroke
			(width 0)
			(type default)
		)
	)
	(wire
		(pts
			(xy 196.85 53.34) (xy 196.85 55.88)
		)
		(stroke
			(width 0)
			(type default)
		)
	)
	(wire
		(pts
			(xy 196.85 53.34) (xy 209.55 53.34)
		)
		(stroke
			(width 0)
			(type default)
		)
	)
	(bus
		(pts
			(xy 95.25 220.98) (xy 95.25 223.52)
		)
		(stroke
			(width 0)
			(type default)
		)
	)
	(wire
		(pts
			(xy 200.66 229.87) (xy 204.47 229.87)
		)
		(stroke
			(width 0)
			(type default)
		)
	)
	(bus
		(pts
			(xy 95.25 233.68) (xy 95.25 236.22)
		)
		(stroke
			(width 0)
			(type default)
		)
	)
	(bus
		(pts
			(xy 95.25 243.84) (xy 95.25 246.38)
		)
		(stroke
			(width 0)
			(type default)
		)
	)
	(wire
		(pts
			(xy 320.04 43.18) (xy 320.04 45.72)
		)
		(stroke
			(width 0)
			(type default)
		)
	)
	(wire
		(pts
			(xy 196.85 25.4) (xy 196.85 27.94)
		)
		(stroke
			(width 0)
			(type default)
		)
	)
	(wire
		(pts
			(xy 275.59 25.4) (xy 275.59 27.94)
		)
		(stroke
			(width 0)
			(type default)
		)
	)
	(wire
		(pts
			(xy 205.74 25.4) (xy 205.74 27.94)
		)
		(stroke
			(width 0)
			(type default)
		)
	)
	(wire
		(pts
			(xy 142.24 83.82) (xy 163.83 83.82)
		)
		(stroke
			(width 0)
			(type default)
		)
	)
	(wire
		(pts
			(xy 325.12 104.14) (xy 325.12 106.68)
		)
		(stroke
			(width 0)
			(type default)
		)
	)
	(wire
		(pts
			(xy 266.7 25.4) (xy 266.7 27.94)
		)
		(stroke
			(width 0)
			(type default)
		)
	)
	(bus
		(pts
			(xy 90.17 90.17) (xy 90.17 92.71)
		)
		(stroke
			(width 0)
			(type default)
		)
	)
	(wire
		(pts
			(xy 91.44 48.26) (xy 107.95 48.26)
		)
		(stroke
			(width 0)
			(type default)
		)
	)
	(wire
		(pts
			(xy 241.3 25.4) (xy 241.3 27.94)
		)
		(stroke
			(width 0)
			(type default)
		)
	)
	(wire
		(pts
			(xy 359.41 104.14) (xy 337.82 104.14)
		)
		(stroke
			(width 0)
			(type default)
		)
	)
	(wire
		(pts
			(xy 241.3 33.02) (xy 241.3 35.56)
		)
		(stroke
			(width 0)
			(type default)
		)
	)
	(wire
		(pts
			(xy 91.44 101.6) (xy 111.76 101.6)
		)
		(stroke
			(width 0)
			(type default)
		)
	)
	(wire
		(pts
			(xy 318.77 104.14) (xy 325.12 104.14)
		)
		(stroke
			(width 0)
			(type default)
		)
	)
	(wire
		(pts
			(xy 218.44 87.63) (xy 224.79 87.63)
		)
		(stroke
			(width 0)
			(type default)
		)
	)
	(wire
		(pts
			(xy 224.79 101.6) (xy 224.79 104.14)
		)
		(stroke
			(width 0)
			(type default)
		)
	)
	(polyline
		(pts
			(xy 13.97 152.4) (xy 406.4 152.4)
		)
		(stroke
			(width 0)
			(type default)
		)
	)
	(polyline
		(pts
			(xy 361.95 68.58) (xy 361.95 38.1)
		)
		(stroke
			(width 0)
			(type default)
		)
	)
	(bus
		(pts
			(xy 90.17 121.92) (xy 165.1 121.92)
		)
		(stroke
			(width 0)
			(type default)
		)
	)
	(wire
		(pts
			(xy 96.52 242.57) (xy 111.76 242.57)
		)
		(stroke
			(width 0)
			(type default)
		)
	)
	(wire
		(pts
			(xy 161.29 33.02) (xy 161.29 35.56)
		)
		(stroke
			(width 0)
			(type default)
		)
	)
	(wire
		(pts
			(xy 204.47 234.95) (xy 204.47 237.49)
		)
		(stroke
			(width 0)
			(type default)
		)
	)
	(wire
		(pts
			(xy 91.44 73.66) (xy 111.76 73.66)
		)
		(stroke
			(width 0)
			(type default)
		)
	)
	(bus
		(pts
			(xy 90.17 107.95) (xy 90.17 113.03)
		)
		(stroke
			(width 0)
			(type default)
		)
	)
	(wire
		(pts
			(xy 96.52 212.09) (xy 111.76 212.09)
		)
		(stroke
			(width 0)
			(type default)
		)
	)
	(bus
		(pts
			(xy 285.75 107.95) (xy 285.75 110.49)
		)
		(stroke
			(width 0)
			(type default)
		)
	)
	(wire
		(pts
			(xy 96.52 245.11) (xy 111.76 245.11)
		)
		(stroke
			(width 0)
			(type default)
		)
	)
	(wire
		(pts
			(xy 311.15 60.96) (xy 320.04 60.96)
		)
		(stroke
			(width 0)
			(type default)
		)
	)
	(wire
		(pts
			(xy 287.02 95.25) (xy 308.61 95.25)
		)
		(stroke
			(width 0)
			(type default)
		)
	)
	(wire
		(pts
			(xy 359.41 95.25) (xy 337.82 95.25)
		)
		(stroke
			(width 0)
			(type default)
		)
	)
	(wire
		(pts
			(xy 342.9 60.96) (xy 351.79 60.96)
		)
		(stroke
			(width 0)
			(type default)
		)
	)
	(wire
		(pts
			(xy 91.44 55.88) (xy 111.76 55.88)
		)
		(stroke
			(width 0)
			(type default)
		)
	)
	(wire
		(pts
			(xy 267.97 104.14) (xy 274.32 104.14)
		)
		(stroke
			(width 0)
			(type default)
		)
	)
	(wire
		(pts
			(xy 257.81 33.02) (xy 257.81 35.56)
		)
		(stroke
			(width 0)
			(type default)
		)
	)
	(bus
		(pts
			(xy 234.95 121.92) (xy 285.75 121.92)
		)
		(stroke
			(width 0)
			(type default)
		)
	)
	(wire
		(pts
			(xy 311.15 59.69) (xy 311.15 60.96)
		)
		(stroke
			(width 0)
			(type default)
		)
	)
	(polyline
		(pts
			(xy 293.37 68.58) (xy 361.95 68.58)
		)
		(stroke
			(width 0)
			(type default)
		)
	)
	(bus
		(pts
			(xy 95.25 236.22) (xy 95.25 238.76)
		)
		(stroke
			(width 0)
			(type default)
		)
	)
	(bus
		(pts
			(xy 171.45 231.14) (xy 171.45 233.68)
		)
		(stroke
			(width 0)
			(type default)
		)
	)
	(bus
		(pts
			(xy 234.95 110.49) (xy 234.95 113.03)
		)
		(stroke
			(width 0)
			(type default)
		)
	)
	(wire
		(pts
			(xy 377.19 87.63) (xy 377.19 90.17)
		)
		(stroke
			(width 0)
			(type default)
		)
	)
	(wire
		(pts
			(xy 274.32 106.68) (xy 274.32 109.22)
		)
		(stroke
			(width 0)
			(type default)
		)
	)
	(wire
		(pts
			(xy 146.05 53.34) (xy 187.96 53.34)
		)
		(stroke
			(width 0)
			(type default)
		)
	)
	(bus
		(pts
			(xy 165.1 100.33) (xy 165.1 102.87)
		)
		(stroke
			(width 0)
			(type default)
		)
	)
	(wire
		(pts
			(xy 146.05 191.77) (xy 146.05 193.04)
		)
		(stroke
			(width 0)
			(type default)
		)
	)
	(bus
		(pts
			(xy 90.17 97.79) (xy 90.17 102.87)
		)
		(stroke
			(width 0)
			(type default)
		)
	)
	(bus
		(pts
			(xy 95.25 231.14) (xy 95.25 233.68)
		)
		(stroke
			(width 0)
			(type default)
		)
	)
	(wire
		(pts
			(xy 320.04 52.07) (xy 320.04 54.61)
		)
		(stroke
			(width 0)
			(type default)
		)
	)
	(wire
		(pts
			(xy 91.44 66.04) (xy 111.76 66.04)
		)
		(stroke
			(width 0)
			(type default)
		)
	)
	(wire
		(pts
			(xy 91.44 111.76) (xy 111.76 111.76)
		)
		(stroke
			(width 0)
			(type default)
		)
	)
	(bus
		(pts
			(xy 171.45 238.76) (xy 171.45 255.27)
		)
		(stroke
			(width 0)
			(type default)
		)
	)
	(bus
		(pts
			(xy 165.1 72.39) (xy 165.1 74.93)
		)
		(stroke
			(width 0)
			(type default)
		)
	)
	(bus
		(pts
			(xy 153.67 218.44) (xy 153.67 220.98)
		)
		(stroke
			(width 0)
			(type default)
		)
	)
	(wire
		(pts
			(xy 193.04 91.44) (xy 213.36 91.44)
		)
		(stroke
			(width 0)
			(type default)
		)
	)
	(wire
		(pts
			(xy 274.32 104.14) (xy 274.32 106.68)
		)
		(stroke
			(width 0)
			(type default)
		)
	)
	(wire
		(pts
			(xy 274.32 92.71) (xy 274.32 95.25)
		)
		(stroke
			(width 0)
			(type default)
		)
	)
	(wire
		(pts
			(xy 146.05 184.15) (xy 146.05 186.69)
		)
		(stroke
			(width 0)
			(type default)
		)
	)
	(bus
		(pts
			(xy 165.1 69.85) (xy 165.1 72.39)
		)
		(stroke
			(width 0)
			(type default)
		)
	)
	(wire
		(pts
			(xy 170.18 25.4) (xy 179.07 25.4)
		)
		(stroke
			(width 0)
			(type default)
		)
	)
	(wire
		(pts
			(xy 325.12 92.71) (xy 325.12 95.25)
		)
		(stroke
			(width 0)
			(type default)
		)
	)
	(polyline
		(pts
			(xy 209.55 220.98) (xy 168.91 220.98)
		)
		(stroke
			(width 0)
			(type default)
		)
	)
	(wire
		(pts
			(xy 308.61 106.68) (xy 287.02 106.68)
		)
		(stroke
			(width 0)
			(type default)
		)
	)
	(wire
		(pts
			(xy 179.07 33.02) (xy 179.07 35.56)
		)
		(stroke
			(width 0)
			(type default)
		)
	)
	(wire
		(pts
			(xy 142.24 66.04) (xy 163.83 66.04)
		)
		(stroke
			(width 0)
			(type default)
		)
	)
	(wire
		(pts
			(xy 300.99 52.07) (xy 311.15 52.07)
		)
		(stroke
			(width 0)
			(type default)
		)
	)
	(bus
		(pts
			(xy 165.1 102.87) (xy 165.1 121.92)
		)
		(stroke
			(width 0)
			(type default)
		)
	)
	(wire
		(pts
			(xy 377.19 86.36) (xy 377.19 87.63)
		)
		(stroke
			(width 0)
			(type default)
		)
	)
	(bus
		(pts
			(xy 95.25 210.82) (xy 95.25 213.36)
		)
		(stroke
			(width 0)
			(type default)
		)
	)
	(bus
		(pts
			(xy 153.67 236.22) (xy 153.67 238.76)
		)
		(stroke
			(width 0)
			(type default)
		)
	)
	(bus
		(pts
			(xy 95.25 205.74) (xy 95.25 208.28)
		)
		(stroke
			(width 0)
			(type default)
		)
	)
	(wire
		(pts
			(xy 257.81 109.22) (xy 236.22 109.22)
		)
		(stroke
			(width 0)
			(type default)
		)
	)
	(wire
		(pts
			(xy 170.18 33.02) (xy 170.18 35.56)
		)
		(stroke
			(width 0)
			(type default)
		)
	)
	(wire
		(pts
			(xy 351.79 59.69) (xy 351.79 60.96)
		)
		(stroke
			(width 0)
			(type default)
		)
	)
	(bus
		(pts
			(xy 95.25 223.52) (xy 95.25 226.06)
		)
		(stroke
			(width 0)
			(type default)
		)
	)
	(wire
		(pts
			(xy 267.97 109.22) (xy 274.32 109.22)
		)
		(stroke
			(width 0)
			(type default)
		)
	)
	(wire
		(pts
			(xy 250.19 25.4) (xy 250.19 27.94)
		)
		(stroke
			(width 0)
			(type default)
		)
	)
	(wire
		(pts
			(xy 187.96 25.4) (xy 196.85 25.4)
		)
		(stroke
			(width 0)
			(type default)
		)
	)
	(wire
		(pts
			(xy 241.3 25.4) (xy 250.19 25.4)
		)
		(stroke
			(width 0)
			(type default)
		)
	)
	(bus
		(pts
			(xy 153.67 238.76) (xy 153.67 257.81)
		)
		(stroke
			(width 0)
			(type default)
		)
	)
	(wire
		(pts
			(xy 274.32 86.36) (xy 274.32 87.63)
		)
		(stroke
			(width 0)
			(type default)
		)
	)
	(bus
		(pts
			(xy 336.55 110.49) (xy 336.55 113.03)
		)
		(stroke
			(width 0)
			(type default)
		)
	)
	(wire
		(pts
			(xy 369.57 111.76) (xy 377.19 111.76)
		)
		(stroke
			(width 0)
			(type default)
		)
	)
	(wire
		(pts
			(xy 91.44 50.8) (xy 111.76 50.8)
		)
		(stroke
			(width 0)
			(type default)
		)
	)
	(wire
		(pts
			(xy 307.34 25.4) (xy 311.15 25.4)
		)
		(stroke
			(width 0)
			(type default)
		)
	)
	(wire
		(pts
			(xy 274.32 109.22) (xy 274.32 111.76)
		)
		(stroke
			(width 0)
			(type default)
		)
	)
	(wire
		(pts
			(xy 311.15 43.18) (xy 320.04 43.18)
		)
		(stroke
			(width 0)
			(type default)
		)
	)
	(wire
		(pts
			(xy 334.01 43.18) (xy 342.9 43.18)
		)
		(stroke
			(width 0)
			(type default)
		)
	)
	(wire
		(pts
			(xy 205.74 33.02) (xy 205.74 35.56)
		)
		(stroke
			(width 0)
			(type default)
		)
	)
	(bus
		(pts
			(xy 191.77 92.71) (xy 191.77 102.87)
		)
		(stroke
			(width 0)
			(type default)
		)
	)
	(wire
		(pts
			(xy 154.94 191.77) (xy 154.94 193.04)
		)
		(stroke
			(width 0)
			(type default)
		)
	)
	(bus
		(pts
			(xy 95.25 228.6) (xy 95.25 231.14)
		)
		(stroke
			(width 0)
			(type default)
		)
	)
	(wire
		(pts
			(xy 91.44 58.42) (xy 111.76 58.42)
		)
		(stroke
			(width 0)
			(type default)
		)
	)
	(wire
		(pts
			(xy 369.57 92.71) (xy 377.19 92.71)
		)
		(stroke
			(width 0)
			(type default)
		)
	)
	(wire
		(pts
			(xy 334.01 52.07) (xy 342.9 52.07)
		)
		(stroke
			(width 0)
			(type default)
		)
	)
	(wire
		(pts
			(xy 147.32 109.22) (xy 147.32 111.76)
		)
		(stroke
			(width 0)
			(type default)
		)
	)
	(wire
		(pts
			(xy 91.44 78.74) (xy 111.76 78.74)
		)
		(stroke
			(width 0)
			(type default)
		)
	)
	(wire
		(pts
			(xy 152.4 33.02) (xy 152.4 35.56)
		)
		(stroke
			(width 0)
			(type default)
		)
	)
	(bus
		(pts
			(xy 191.77 105.41) (xy 191.77 121.92)
		)
		(stroke
			(width 0)
			(type default)
		)
	)
	(wire
		(pts
			(xy 267.97 95.25) (xy 274.32 95.25)
		)
		(stroke
			(width 0)
			(type default)
		)
	)
	(wire
		(pts
			(xy 320.04 43.18) (xy 334.01 43.18)
		)
		(stroke
			(width 0)
			(type default)
		)
	)
	(bus
		(pts
			(xy 153.67 257.81) (xy 168.91 257.81)
		)
		(stroke
			(width 0)
			(type default)
		)
	)
	(wire
		(pts
			(xy 152.4 219.71) (xy 137.16 219.71)
		)
		(stroke
			(width 0)
			(type default)
		)
	)
	(wire
		(pts
			(xy 100.33 30.48) (xy 100.33 33.02)
		)
		(stroke
			(width 0)
			(type default)
		)
	)
	(bus
		(pts
			(xy 165.1 62.23) (xy 165.1 64.77)
		)
		(stroke
			(width 0)
			(type default)
		)
	)
	(wire
		(pts
			(xy 377.19 109.22) (xy 377.19 111.76)
		)
		(stroke
			(width 0)
			(type default)
		)
	)
	(wire
		(pts
			(xy 100.33 38.1) (xy 100.33 39.37)
		)
		(stroke
			(width 0)
			(type default)
		)
	)
	(wire
		(pts
			(xy 172.72 237.49) (xy 190.5 237.49)
		)
		(stroke
			(width 0)
			(type default)
		)
	)
	(bus
		(pts
			(xy 336.55 107.95) (xy 336.55 110.49)
		)
		(stroke
			(width 0)
			(type default)
		)
	)
	(wire
		(pts
			(xy 91.44 106.68) (xy 111.76 106.68)
		)
		(stroke
			(width 0)
			(type default)
		)
	)
	(wire
		(pts
			(xy 152.4 25.4) (xy 146.05 25.4)
		)
		(stroke
			(width 0)
			(type default)
		)
	)
	(polyline
		(pts
			(xy 209.55 220.98) (xy 209.55 260.35)
		)
		(stroke
			(width 0)
			(type default)
		)
	)
	(wire
		(pts
			(xy 96.52 232.41) (xy 111.76 232.41)
		)
		(stroke
			(width 0)
			(type default)
		)
	)
	(wire
		(pts
			(xy 142.24 55.88) (xy 146.05 55.88)
		)
		(stroke
			(width 0)
			(type default)
		)
	)
	(wire
		(pts
			(xy 96.52 214.63) (xy 111.76 214.63)
		)
		(stroke
			(width 0)
			(type default)
		)
	)
	(bus
		(pts
			(xy 165.1 64.77) (xy 165.1 67.31)
		)
		(stroke
			(width 0)
			(type default)
		)
	)
	(wire
		(pts
			(xy 318.77 109.22) (xy 325.12 109.22)
		)
		(stroke
			(width 0)
			(type default)
		)
	)
	(bus
		(pts
			(xy 234.95 93.98) (xy 234.95 96.52)
		)
		(stroke
			(width 0)
			(type default)
		)
	)
	(bus
		(pts
			(xy 165.1 82.55) (xy 165.1 85.09)
		)
		(stroke
			(width 0)
			(type default)
		)
	)
	(wire
		(pts
			(xy 334.01 60.96) (xy 342.9 60.96)
		)
		(stroke
			(width 0)
			(type default)
		)
	)
	(bus
		(pts
			(xy 90.17 72.39) (xy 90.17 74.93)
		)
		(stroke
			(width 0)
			(type default)
		)
	)
	(wire
		(pts
			(xy 142.24 86.36) (xy 163.83 86.36)
		)
		(stroke
			(width 0)
			(type default)
		)
	)
	(wire
		(pts
			(xy 91.44 104.14) (xy 111.76 104.14)
		)
		(stroke
			(width 0)
			(type default)
		)
	)
	(bus
		(pts
			(xy 90.17 77.47) (xy 90.17 80.01)
		)
		(stroke
			(width 0)
			(type default)
		)
	)
	(wire
		(pts
			(xy 257.81 104.14) (xy 236.22 104.14)
		)
		(stroke
			(width 0)
			(type default)
		)
	)
	(wire
		(pts
			(xy 266.7 25.4) (xy 275.59 25.4)
		)
		(stroke
			(width 0)
			(type default)
		)
	)
	(wire
		(pts
			(xy 223.52 25.4) (xy 232.41 25.4)
		)
		(stroke
			(width 0)
			(type default)
		)
	)
	(wire
		(pts
			(xy 214.63 25.4) (xy 223.52 25.4)
		)
		(stroke
			(width 0)
			(type default)
		)
	)
	(bus
		(pts
			(xy 95.25 248.92) (xy 95.25 257.81)
		)
		(stroke
			(width 0)
			(type default)
		)
	)
	(wire
		(pts
			(xy 213.36 104.14) (xy 193.04 104.14)
		)
		(stroke
			(width 0)
			(type default)
		)
	)
	(wire
		(pts
			(xy 152.4 237.49) (xy 137.16 237.49)
		)
		(stroke
			(width 0)
			(type default)
		)
	)
	(wire
		(pts
			(xy 142.24 76.2) (xy 163.83 76.2)
		)
		(stroke
			(width 0)
			(type default)
		)
	)
	(wire
		(pts
			(xy 325.12 87.63) (xy 325.12 90.17)
		)
		(stroke
			(width 0)
			(type default)
		)
	)
	(wire
		(pts
			(xy 172.72 232.41) (xy 190.5 232.41)
		)
		(stroke
			(width 0)
			(type default)
		)
	)
	(wire
		(pts
			(xy 342.9 52.07) (xy 342.9 54.61)
		)
		(stroke
			(width 0)
			(type default)
		)
	)
	(wire
		(pts
			(xy 146.05 50.8) (xy 146.05 48.26)
		)
		(stroke
			(width 0)
			(type default)
		)
	)
	(bus
		(pts
			(xy 90.17 54.61) (xy 90.17 57.15)
		)
		(stroke
			(width 0)
			(type default)
		)
	)
	(bus
		(pts
			(xy 234.95 91.44) (xy 234.95 93.98)
		)
		(stroke
			(width 0)
			(type default)
		)
	)
	(wire
		(pts
			(xy 146.05 184.15) (xy 154.94 184.15)
		)
		(stroke
			(width 0)
			(type default)
		)
	)
	(wire
		(pts
			(xy 369.57 104.14) (xy 377.19 104.14)
		)
		(stroke
			(width 0)
			(type default)
		)
	)
	(bus
		(pts
			(xy 90.17 92.71) (xy 90.17 95.25)
		)
		(stroke
			(width 0)
			(type default)
		)
	)
	(wire
		(pts
			(xy 320.04 60.96) (xy 334.01 60.96)
		)
		(stroke
			(width 0)
			(type default)
		)
	)
	(wire
		(pts
			(xy 96.52 201.93) (xy 111.76 201.93)
		)
		(stroke
			(width 0)
			(type default)
		)
	)
	(wire
		(pts
			(xy 250.19 25.4) (xy 257.81 25.4)
		)
		(stroke
			(width 0)
			(type default)
		)
	)
	(wire
		(pts
			(xy 91.44 86.36) (xy 111.76 86.36)
		)
		(stroke
			(width 0)
			(type default)
		)
	)
	(wire
		(pts
			(xy 187.96 60.96) (xy 187.96 63.5)
		)
		(stroke
			(width 0)
			(type default)
		)
	)
	(wire
		(pts
			(xy 266.7 33.02) (xy 266.7 35.56)
		)
		(stroke
			(width 0)
			(type default)
		)
	)
	(bus
		(pts
			(xy 336.55 96.52) (xy 336.55 105.41)
		)
		(stroke
			(width 0)
			(type default)
		)
	)
	(wire
		(pts
			(xy 267.97 92.71) (xy 274.32 92.71)
		)
		(stroke
			(width 0)
			(type default)
		)
	)
	(polyline
		(pts
			(xy 383.54 76.2) (xy 187.96 76.2)
		)
		(stroke
			(width 0)
			(type default)
		)
	)
	(wire
		(pts
			(xy 318.77 95.25) (xy 325.12 95.25)
		)
		(stroke
			(width 0)
			(type default)
		)
	)
	(polyline
		(pts
			(xy 209.55 260.35) (xy 168.91 260.35)
		)
		(stroke
			(width 0)
			(type default)
		)
	)
	(bus
		(pts
			(xy 153.67 223.52) (xy 153.67 226.06)
		)
		(stroke
			(width 0)
			(type default)
		)
	)
	(bus
		(pts
			(xy 285.75 113.03) (xy 285.75 121.92)
		)
		(stroke
			(width 0)
			(type default)
		)
	)
	(wire
		(pts
			(xy 152.4 25.4) (xy 161.29 25.4)
		)
		(stroke
			(width 0)
			(type default)
		)
	)
	(bus
		(pts
			(xy 90.17 87.63) (xy 90.17 90.17)
		)
		(stroke
			(width 0)
			(type default)
		)
	)
	(wire
		(pts
			(xy 223.52 25.4) (xy 223.52 27.94)
		)
		(stroke
			(width 0)
			(type default)
		)
	)
	(bus
		(pts
			(xy 165.1 85.09) (xy 165.1 87.63)
		)
		(stroke
			(width 0)
			(type default)
		)
	)
	(bus
		(pts
			(xy 285.75 96.52) (xy 285.75 105.41)
		)
		(stroke
			(width 0)
			(type default)
		)
	)
	(wire
		(pts
			(xy 91.44 83.82) (xy 111.76 83.82)
		)
		(stroke
			(width 0)
			(type default)
		)
	)
	(wire
		(pts
			(xy 139.7 184.15) (xy 146.05 184.15)
		)
		(stroke
			(width 0)
			(type default)
		)
	)
	(bus
		(pts
			(xy 171.45 255.27) (xy 168.91 257.81)
		)
		(stroke
			(width 0)
			(type default)
		)
	)
	(bus
		(pts
			(xy 153.67 220.98) (xy 153.67 223.52)
		)
		(stroke
			(width 0)
			(type default)
		)
	)
	(wire
		(pts
			(xy 152.4 25.4) (xy 152.4 27.94)
		)
		(stroke
			(width 0)
			(type default)
		)
	)
	(wire
		(pts
			(xy 96.52 227.33) (xy 111.76 227.33)
		)
		(stroke
			(width 0)
			(type default)
		)
	)
	(wire
		(pts
			(xy 205.74 25.4) (xy 214.63 25.4)
		)
		(stroke
			(width 0)
			(type default)
		)
	)
	(wire
		(pts
			(xy 311.15 60.96) (xy 311.15 62.23)
		)
		(stroke
			(width 0)
			(type default)
		)
	)
	(bus
		(pts
			(xy 336.55 93.98) (xy 336.55 96.52)
		)
		(stroke
			(width 0)
			(type default)
		)
	)
	(bus
		(pts
			(xy 191.77 121.92) (xy 234.95 121.92)
		)
		(stroke
			(width 0)
			(type default)
		)
	)
	(bus
		(pts
			(xy 153.67 208.28) (xy 153.67 210.82)
		)
		(stroke
			(width 0)
			(type default)
		)
	)
	(wire
		(pts
			(xy 359.41 109.22) (xy 337.82 109.22)
		)
		(stroke
			(width 0)
			(type default)
		)
	)
	(wire
		(pts
			(xy 275.59 33.02) (xy 275.59 35.56)
		)
		(stroke
			(width 0)
			(type default)
		)
	)
	(wire
		(pts
			(xy 142.24 104.14) (xy 156.21 104.14)
		)
		(stroke
			(width 0)
			(type default)
		)
	)
	(wire
		(pts
			(xy 224.79 86.36) (xy 224.79 87.63)
		)
		(stroke
			(width 0)
			(type default)
		)
	)
	(bus
		(pts
			(xy 90.17 74.93) (xy 90.17 77.47)
		)
		(stroke
			(width 0)
			(type default)
		)
	)
	(bus
		(pts
			(xy 234.95 113.03) (xy 234.95 121.92)
		)
		(stroke
			(width 0)
			(type default)
		)
	)
	(wire
		(pts
			(xy 218.44 91.44) (xy 224.79 91.44)
		)
		(stroke
			(width 0)
			(type default)
		)
	)
	(wire
		(pts
			(xy 308.61 90.17) (xy 287.02 90.17)
		)
		(stroke
			(width 0)
			(type default)
		)
	)
	(wire
		(pts
			(xy 318.77 111.76) (xy 325.12 111.76)
		)
		(stroke
			(width 0)
			(type default)
		)
	)
	(bus
		(pts
			(xy 335.28 121.92) (xy 336.55 120.65)
		)
		(stroke
			(width 0)
			(type default)
		)
	)
	(wire
		(pts
			(xy 274.32 87.63) (xy 274.32 90.17)
		)
		(stroke
			(width 0)
			(type default)
		)
	)
	(wire
		(pts
			(xy 287.02 104.14) (xy 308.61 104.14)
		)
		(stroke
			(width 0)
			(type default)
		)
	)
	(wire
		(pts
			(xy 156.21 113.03) (xy 156.21 114.3)
		)
		(stroke
			(width 0)
			(type default)
		)
	)
	(wire
		(pts
			(xy 359.41 111.76) (xy 337.82 111.76)
		)
		(stroke
			(width 0)
			(type default)
		)
	)
	(wire
		(pts
			(xy 152.4 229.87) (xy 137.16 229.87)
		)
		(stroke
			(width 0)
			(type default)
		)
	)
	(wire
		(pts
			(xy 107.95 48.26) (xy 107.95 30.48)
		)
		(stroke
			(width 0)
			(type default)
		)
	)
	(wire
		(pts
			(xy 214.63 33.02) (xy 214.63 35.56)
		)
		(stroke
			(width 0)
			(type default)
		)
	)
	(wire
		(pts
			(xy 91.44 81.28) (xy 111.76 81.28)
		)
		(stroke
			(width 0)
			(type default)
		)
	)
	(bus
		(pts
			(xy 285.75 105.41) (xy 285.75 107.95)
		)
		(stroke
			(width 0)
			(type default)
		)
	)
	(wire
		(pts
			(xy 137.16 245.11) (xy 140.97 245.11)
		)
		(stroke
			(width 0)
			(type default)
		)
	)
	(wire
		(pts
			(xy 152.4 212.09) (xy 137.16 212.09)
		)
		(stroke
			(width 0)
			(type default)
		)
	)
	(wire
		(pts
			(xy 257.81 25.4) (xy 257.81 27.94)
		)
		(stroke
			(width 0)
			(type default)
		)
	)
	(wire
		(pts
			(xy 91.44 71.12) (xy 111.76 71.12)
		)
		(stroke
			(width 0)
			(type default)
		)
	)
	(wire
		(pts
			(xy 274.32 95.25) (xy 274.32 104.14)
		)
		(stroke
			(width 0)
			(type default)
		)
	)
	(bus
		(pts
			(xy 95.25 200.66) (xy 95.25 203.2)
		)
		(stroke
			(width 0)
			(type default)
		)
	)
	(bus
		(pts
			(xy 95.25 246.38) (xy 95.25 248.92)
		)
		(stroke
			(width 0)
			(type default)
		)
	)
	(bus
		(pts
			(xy 153.67 231.14) (xy 153.67 233.68)
		)
		(stroke
			(width 0)
			(type default)
		)
	)
	(wire
		(pts
			(xy 250.19 33.02) (xy 250.19 35.56)
		)
		(stroke
			(width 0)
			(type default)
		)
	)
	(bus
		(pts
			(xy 90.17 67.31) (xy 90.17 69.85)
		)
		(stroke
			(width 0)
			(type default)
		)
	)
	(bus
		(pts
			(xy 90.17 59.69) (xy 90.17 62.23)
		)
		(stroke
			(width 0)
			(type default)
		)
	)
	(wire
		(pts
			(xy 142.24 96.52) (xy 163.83 96.52)
		)
		(stroke
			(width 0)
			(type default)
		)
	)
	(wire
		(pts
			(xy 334.01 43.18) (xy 334.01 45.72)
		)
		(stroke
			(width 0)
			(type default)
		)
	)
	(wire
		(pts
			(xy 161.29 25.4) (xy 170.18 25.4)
		)
		(stroke
			(width 0)
			(type default)
		)
	)
	(wire
		(pts
			(xy 325.12 106.68) (xy 325.12 109.22)
		)
		(stroke
			(width 0)
			(type default)
		)
	)
	(wire
		(pts
			(xy 91.44 76.2) (xy 111.76 76.2)
		)
		(stroke
			(width 0)
			(type default)
		)
	)
	(wire
		(pts
			(xy 179.07 25.4) (xy 187.96 25.4)
		)
		(stroke
			(width 0)
			(type default)
		)
	)
	(bus
		(pts
			(xy 90.17 82.55) (xy 90.17 85.09)
		)
		(stroke
			(width 0)
			(type default)
		)
	)
	(wire
		(pts
			(xy 200.66 234.95) (xy 204.47 234.95)
		)
		(stroke
			(width 0)
			(type default)
		)
	)
	(wire
		(pts
			(xy 142.24 78.74) (xy 163.83 78.74)
		)
		(stroke
			(width 0)
			(type default)
		)
	)
	(bus
		(pts
			(xy 171.45 233.68) (xy 171.45 236.22)
		)
		(stroke
			(width 0)
			(type default)
		)
	)
	(wire
		(pts
			(xy 96.52 240.03) (xy 111.76 240.03)
		)
		(stroke
			(width 0)
			(type default)
		)
	)
	(bus
		(pts
			(xy 90.17 49.53) (xy 90.17 52.07)
		)
		(stroke
			(width 0)
			(type default)
		)
	)
	(wire
		(pts
			(xy 173.99 184.15) (xy 173.99 182.88)
		)
		(stroke
			(width 0)
			(type default)
		)
	)
	(wire
		(pts
			(xy 320.04 59.69) (xy 320.04 60.96)
		)
		(stroke
			(width 0)
			(type default)
		)
	)
	(wire
		(pts
			(xy 168.91 184.15) (xy 173.99 184.15)
		)
		(stroke
			(width 0)
			(type default)
		)
	)
	(wire
		(pts
			(xy 232.41 25.4) (xy 241.3 25.4)
		)
		(stroke
			(width 0)
			(type default)
		)
	)
	(wire
		(pts
			(xy 342.9 52.07) (xy 351.79 52.07)
		)
		(stroke
			(width 0)
			(type default)
		)
	)
	(bus
		(pts
			(xy 171.45 236.22) (xy 171.45 238.76)
		)
		(stroke
			(width 0)
			(type default)
		)
	)
	(bus
		(pts
			(xy 165.1 95.25) (xy 165.1 97.79)
		)
		(stroke
			(width 0)
			(type default)
		)
	)
	(bus
		(pts
			(xy 90.17 85.09) (xy 90.17 87.63)
		)
		(stroke
			(width 0)
			(type default)
		)
	)
	(wire
		(pts
			(xy 142.24 101.6) (xy 163.83 101.6)
		)
		(stroke
			(width 0)
			(type default)
		)
	)
	(wire
		(pts
			(xy 96.52 207.01) (xy 111.76 207.01)
		)
		(stroke
			(width 0)
			(type default)
		)
	)
	(wire
		(pts
			(xy 146.05 55.88) (xy 146.05 53.34)
		)
		(stroke
			(width 0)
			(type default)
		)
	)
	(wire
		(pts
			(xy 107.95 48.26) (xy 111.76 48.26)
		)
		(stroke
			(width 0)
			(type default)
		)
	)
	(bus
		(pts
			(xy 90.17 102.87) (xy 90.17 105.41)
		)
		(stroke
			(width 0)
			(type default)
		)
	)
	(bus
		(pts
			(xy 234.95 96.52) (xy 234.95 105.41)
		)
		(stroke
			(width 0)
			(type default)
		)
	)
	(wire
		(pts
			(xy 146.05 25.4) (xy 146.05 48.26)
		)
		(stroke
			(width 0)
			(type default)
		)
	)
	(wire
		(pts
			(xy 232.41 33.02) (xy 232.41 35.56)
		)
		(stroke
			(width 0)
			(type default)
		)
	)
	(wire
		(pts
			(xy 369.57 106.68) (xy 377.19 106.68)
		)
		(stroke
			(width 0)
			(type default)
		)
	)
	(wire
		(pts
			(xy 275.59 25.4) (xy 307.34 25.4)
		)
		(stroke
			(width 0)
			(type default)
		)
	)
	(wire
		(pts
			(xy 91.44 93.98) (xy 111.76 93.98)
		)
		(stroke
			(width 0)
			(type default)
		)
	)
	(wire
		(pts
			(xy 351.79 50.8) (xy 351.79 52.07)
		)
		(stroke
			(width 0)
			(type default)
		)
	)
	(wire
		(pts
			(xy 204.47 227.33) (xy 204.47 229.87)
		)
		(stroke
			(width 0)
			(type default)
		)
	)
	(wire
		(pts
			(xy 325.12 86.36) (xy 325.12 87.63)
		)
		(stroke
			(width 0)
			(type default)
		)
	)
	(wire
		(pts
			(xy 325.12 109.22) (xy 325.12 111.76)
		)
		(stroke
			(width 0)
			(type default)
		)
	)
	(wire
		(pts
			(xy 152.4 209.55) (xy 137.16 209.55)
		)
		(stroke
			(width 0)
			(type default)
		)
	)
	(wire
		(pts
			(xy 267.97 87.63) (xy 274.32 87.63)
		)
		(stroke
			(width 0)
			(type default)
		)
	)
	(polyline
		(pts
			(xy 293.37 38.1) (xy 293.37 68.58)
		)
		(stroke
			(width 0)
			(type default)
		)
	)
	(wire
		(pts
			(xy 142.24 53.34) (xy 146.05 53.34)
		)
		(stroke
			(width 0)
			(type default)
		)
	)
	(bus
		(pts
			(xy 285.75 110.49) (xy 285.75 113.03)
		)
		(stroke
			(width 0)
			(type default)
		)
	)
	(label "DDR.A15"
		(at 95.25 88.9 0)
		(effects
			(font
				(size 1.27 1.27)
			)
			(justify left bottom)
		)
	)
	(label "SRAM.A12"
		(at 99.06 229.87 0)
		(effects
			(font
				(size 1.27 1.27)
			)
			(justify left bottom)
		)
	)
	(label "DDR.~{WE}"
		(at 243.84 92.71 0)
		(effects
			(font
				(size 1.27 1.27)
			)
			(justify left bottom)
		)
	)
	(label "DDR.A7"
		(at 95.25 68.58 0)
		(effects
			(font
				(size 1.27 1.27)
			)
			(justify left bottom)
		)
	)
	(label "DDR.DQ3"
		(at 149.86 68.58 0)
		(effects
			(font
				(size 1.27 1.27)
			)
			(justify left bottom)
		)
	)
	(label "DDR.A12"
		(at 95.25 81.28 0)
		(effects
			(font
				(size 1.27 1.27)
			)
			(justify left bottom)
		)
	)
	(label "DDR.A4"
		(at 95.25 60.96 0)
		(effects
			(font
				(size 1.27 1.27)
			)
			(justify left bottom)
		)
	)
	(label "DDR.BA1"
		(at 95.25 93.98 0)
		(effects
			(font
				(size 1.27 1.27)
			)
			(justify left bottom)
		)
	)
	(label "SRAM.A4"
		(at 99.06 209.55 0)
		(effects
			(font
				(size 1.27 1.27)
			)
			(justify left bottom)
		)
	)
	(label "SRAM.A0"
		(at 99.06 199.39 0)
		(effects
			(font
				(size 1.27 1.27)
			)
			(justify left bottom)
		)
	)
	(label "DDR.DQ5"
		(at 149.86 73.66 0)
		(effects
			(font
				(size 1.27 1.27)
			)
			(justify left bottom)
		)
	)
	(label "DDR.BA1"
		(at 294.64 106.68 0)
		(effects
			(font
				(size 1.27 1.27)
			)
			(justify left bottom)
		)
	)
	(label "SRAM.A18"
		(at 99.06 245.11 0)
		(effects
			(font
				(size 1.27 1.27)
			)
			(justify left bottom)
		)
	)
	(label "SRAM.DQ5"
		(at 140.97 219.71 0)
		(effects
			(font
				(size 1.27 1.27)
			)
			(justify left bottom)
		)
	)
	(label "DDR.DQS_P"
		(at 149.86 81.28 0)
		(effects
			(font
				(size 1.27 1.27)
			)
			(justify left bottom)
		)
	)
	(label "DDR.A3"
		(at 294.64 90.17 0)
		(effects
			(font
				(size 1.27 1.27)
			)
			(justify left bottom)
		)
	)
	(label "DDR.~{CS}"
		(at 243.84 90.17 0)
		(effects
			(font
				(size 1.27 1.27)
			)
			(justify left bottom)
		)
	)
	(label "SRAM.~{WE}"
		(at 175.26 229.87 0)
		(effects
			(font
				(size 1.27 1.27)
			)
			(justify left bottom)
		)
	)
	(label "SRAM.A14"
		(at 99.06 234.95 0)
		(effects
			(font
				(size 1.27 1.27)
			)
			(justify left bottom)
		)
	)
	(label "DDR.A6"
		(at 345.44 90.17 0)
		(effects
			(font
				(size 1.27 1.27)
			)
			(justify left bottom)
		)
	)
	(label "SRAM.~{CE}"
		(at 175.26 234.95 0)
		(effects
			(font
				(size 1.27 1.27)
			)
			(justify left bottom)
		)
	)
	(label "SRAM.CE2"
		(at 175.26 237.49 0)
		(effects
			(font
				(size 1.27 1.27)
			)
			(justify left bottom)
		)
	)
	(label "DDR.A5"
		(at 243.84 111.76 0)
		(effects
			(font
				(size 1.27 1.27)
			)
			(justify left bottom)
		)
	)
	(label "DDR.A2"
		(at 294.64 87.63 0)
		(effects
			(font
				(size 1.27 1.27)
			)
			(justify left bottom)
		)
	)
	(label "DDR.A11"
		(at 345.44 87.63 0)
		(effects
			(font
				(size 1.27 1.27)
			)
			(justify left bottom)
		)
	)
	(label "SRAM.A9"
		(at 99.06 222.25 0)
		(effects
			(font
				(size 1.27 1.27)
			)
			(justify left bottom)
		)
	)
	(label "DDR.A15"
		(at 345.44 111.76 0)
		(effects
			(font
				(size 1.27 1.27)
			)
			(justify left bottom)
		)
	)
	(label "SRAM.A10"
		(at 99.06 224.79 0)
		(effects
			(font
				(size 1.27 1.27)
			)
			(justify left bottom)
		)
	)
	(label "DDR.A14"
		(at 345.44 92.71 0)
		(effects
			(font
				(size 1.27 1.27)
			)
			(justify left bottom)
		)
	)
	(label "DDR.CKE"
		(at 95.25 101.6 0)
		(effects
			(font
				(size 1.27 1.27)
			)
			(justify left bottom)
		)
	)
	(label "DDR.A14"
		(at 95.25 86.36 0)
		(effects
			(font
				(size 1.27 1.27)
			)
			(justify left bottom)
		)
	)
	(label "SRAM.A6"
		(at 99.06 214.63 0)
		(effects
			(font
				(size 1.27 1.27)
			)
			(justify left bottom)
		)
	)
	(label "SRAM.A11"
		(at 99.06 227.33 0)
		(effects
			(font
				(size 1.27 1.27)
			)
			(justify left bottom)
		)
	)
	(label "DDR.CK_N"
		(at 95.25 106.68 0)
		(effects
			(font
				(size 1.27 1.27)
			)
			(justify left bottom)
		)
	)
	(label "DDR.DQ7"
		(at 149.86 78.74 0)
		(effects
			(font
				(size 1.27 1.27)
			)
			(justify left bottom)
		)
	)
	(label "DDR.A11"
		(at 95.25 78.74 0)
		(effects
			(font
				(size 1.27 1.27)
			)
			(justify left bottom)
		)
	)
	(label "SRAM.~{OE}"
		(at 149.86 234.95 180)
		(effects
			(font
				(size 1.27 1.27)
			)
			(justify right bottom)
		)
	)
	(label "SRAM.~{OE}"
		(at 175.26 232.41 0)
		(effects
			(font
				(size 1.27 1.27)
			)
			(justify left bottom)
		)
	)
	(label "DDR.~{CAS}"
		(at 345.44 104.14 0)
		(effects
			(font
				(size 1.27 1.27)
			)
			(justify left bottom)
		)
	)
	(label "DDR.~{RESET}"
		(at 95.25 48.26 0)
		(effects
			(font
				(size 1.27 1.27)
			)
			(justify left bottom)
		)
	)
	(label "DDR.A8"
		(at 345.44 95.25 0)
		(effects
			(font
				(size 1.27 1.27)
			)
			(justify left bottom)
		)
	)
	(label "SRAM.DQ7"
		(at 140.97 224.79 0)
		(effects
			(font
				(size 1.27 1.27)
			)
			(justify left bottom)
		)
	)
	(label "DDR.CK_P"
		(at 195.58 101.6 0)
		(effects
			(font
				(size 1.27 1.27)
			)
			(justify left bottom)
		)
	)
	(label "SRAM.A5"
		(at 99.06 212.09 0)
		(effects
			(font
				(size 1.27 1.27)
			)
			(justify left bottom)
		)
	)
	(label "SRAM.A7"
		(at 99.06 217.17 0)
		(effects
			(font
				(size 1.27 1.27)
			)
			(justify left bottom)
		)
	)
	(label "DDR.~{WE}"
		(at 148.59 93.98 0)
		(effects
			(font
				(size 1.27 1.27)
			)
			(justify left bottom)
		)
	)
	(label "DDR.DQS_N"
		(at 149.86 83.82 0)
		(effects
			(font
				(size 1.27 1.27)
			)
			(justify left bottom)
		)
	)
	(label "DDR.A10"
		(at 95.25 76.2 0)
		(effects
			(font
				(size 1.27 1.27)
			)
			(justify left bottom)
		)
	)
	(label "SRAM.DQ2"
		(at 140.97 212.09 0)
		(effects
			(font
				(size 1.27 1.27)
			)
			(justify left bottom)
		)
	)
	(label "DDR.A3"
		(at 95.25 58.42 0)
		(effects
			(font
				(size 1.27 1.27)
			)
			(justify left bottom)
		)
	)
	(label "DDR.BA2"
		(at 243.84 87.63 0)
		(effects
			(font
				(size 1.27 1.27)
			)
			(justify left bottom)
		)
	)
	(label "DDR.A0"
		(at 95.25 50.8 0)
		(effects
			(font
				(size 1.27 1.27)
			)
			(justify left bottom)
		)
	)
	(label "DDR.A0"
		(at 294.64 92.71 0)
		(effects
			(font
				(size 1.27 1.27)
			)
			(justify left bottom)
		)
	)
	(label "SRAM.~{WE}"
		(at 149.86 237.49 180)
		(effects
			(font
				(size 1.27 1.27)
			)
			(justify right bottom)
		)
	)
	(label "DDR.DM"
		(at 149.86 86.36 0)
		(effects
			(font
				(size 1.27 1.27)
			)
			(justify left bottom)
		)
	)
	(label "DDR.A10"
		(at 345.44 109.22 0)
		(effects
			(font
				(size 1.27 1.27)
			)
			(justify left bottom)
		)
	)
	(label "DDR.CK_N"
		(at 195.58 104.14 0)
		(effects
			(font
				(size 1.27 1.27)
			)
			(justify left bottom)
		)
	)
	(label "DDR.A4"
		(at 294.64 111.76 0)
		(effects
			(font
				(size 1.27 1.27)
			)
			(justify left bottom)
		)
	)
	(label "SRAM.A16"
		(at 99.06 240.03 0)
		(effects
			(font
				(size 1.27 1.27)
			)
			(justify left bottom)
		)
	)
	(label "DDR.A2"
		(at 95.25 55.88 0)
		(effects
			(font
				(size 1.27 1.27)
			)
			(justify left bottom)
		)
	)
	(label "SRAM.A15"
		(at 99.06 237.49 0)
		(effects
			(font
				(size 1.27 1.27)
			)
			(justify left bottom)
		)
	)
	(label "SRAM.A8"
		(at 99.06 219.71 0)
		(effects
			(font
				(size 1.27 1.27)
			)
			(justify left bottom)
		)
	)
	(label "DDR.~{CS}"
		(at 148.59 101.6 0)
		(effects
			(font
				(size 1.27 1.27)
			)
			(justify left bottom)
		)
	)
	(label "DDR.BA2"
		(at 95.25 96.52 0)
		(effects
			(font
				(size 1.27 1.27)
			)
			(justify left bottom)
		)
	)
	(label "SRAM.~{CE}"
		(at 149.86 229.87 180)
		(effects
			(font
				(size 1.27 1.27)
			)
			(justify right bottom)
		)
	)
	(label "DDR.CK_P"
		(at 95.25 104.14 0)
		(effects
			(font
				(size 1.27 1.27)
			)
			(justify left bottom)
		)
	)
	(label "DDR.A9"
		(at 95.25 73.66 0)
		(effects
			(font
				(size 1.27 1.27)
			)
			(justify left bottom)
		)
	)
	(label "SRAM.A17"
		(at 99.06 242.57 0)
		(effects
			(font
				(size 1.27 1.27)
			)
			(justify left bottom)
		)
	)
	(label "SRAM.A13"
		(at 99.06 232.41 0)
		(effects
			(font
				(size 1.27 1.27)
			)
			(justify left bottom)
		)
	)
	(label "DDR.A12"
		(at 294.64 104.14 0)
		(effects
			(font
				(size 1.27 1.27)
			)
			(justify left bottom)
		)
	)
	(label "SRAM.DQ4"
		(at 140.97 217.17 0)
		(effects
			(font
				(size 1.27 1.27)
			)
			(justify left bottom)
		)
	)
	(label "DDR.DM"
		(at 194.31 87.63 0)
		(effects
			(font
				(size 1.27 1.27)
			)
			(justify left bottom)
		)
	)
	(label "DDR.A1"
		(at 294.64 109.22 0)
		(effects
			(font
				(size 1.27 1.27)
			)
			(justify left bottom)
		)
	)
	(label "DDR.DQ0"
		(at 149.86 60.96 0)
		(effects
			(font
				(size 1.27 1.27)
			)
			(justify left bottom)
		)
	)
	(label "DDR.BA0"
		(at 95.25 91.44 0)
		(effects
			(font
				(size 1.27 1.27)
			)
			(justify left bottom)
		)
	)
	(label "DDR.A9"
		(at 243.84 109.22 0)
		(effects
			(font
				(size 1.27 1.27)
			)
			(justify left bottom)
		)
	)
	(label "DDR.DQ2"
		(at 149.86 66.04 0)
		(effects
			(font
				(size 1.27 1.27)
			)
			(justify left bottom)
		)
	)
	(label "DDR_ZQ"
		(at 148.59 104.14 0)
		(effects
			(font
				(size 1.27 1.27)
			)
			(justify left bottom)
		)
	)
	(label "DDR.CKE"
		(at 345.44 106.68 0)
		(effects
			(font
				(size 1.27 1.27)
			)
			(justify left bottom)
		)
	)
	(label "SRAM.DQ0"
		(at 140.97 207.01 0)
		(effects
			(font
				(size 1.27 1.27)
			)
			(justify left bottom)
		)
	)
	(label "DDR.DQ4"
		(at 149.86 71.12 0)
		(effects
			(font
				(size 1.27 1.27)
			)
			(justify left bottom)
		)
	)
	(label "DDR.BA0"
		(at 294.64 95.25 0)
		(effects
			(font
				(size 1.27 1.27)
			)
			(justify left bottom)
		)
	)
	(label "SRAM.A19"
		(at 99.06 247.65 0)
		(effects
			(font
				(size 1.27 1.27)
			)
			(justify left bottom)
		)
	)
	(label "SRAM.CE2"
		(at 149.86 232.41 180)
		(effects
			(font
				(size 1.27 1.27)
			)
			(justify right bottom)
		)
	)
	(label "DDR.ODT"
		(at 243.84 95.25 0)
		(effects
			(font
				(size 1.27 1.27)
			)
			(justify left bottom)
		)
	)
	(label "DDR.A13"
		(at 95.25 83.82 0)
		(effects
			(font
				(size 1.27 1.27)
			)
			(justify left bottom)
		)
	)
	(label "SRAM.A2"
		(at 99.06 204.47 0)
		(effects
			(font
				(size 1.27 1.27)
			)
			(justify left bottom)
		)
	)
	(label "DDR.A13"
		(at 243.84 104.14 0)
		(effects
			(font
				(size 1.27 1.27)
			)
			(justify left bottom)
		)
	)
	(label "DDR.A7"
		(at 243.84 106.68 0)
		(effects
			(font
				(size 1.27 1.27)
			)
			(justify left bottom)
		)
	)
	(label "DDR.A8"
		(at 95.25 71.12 0)
		(effects
			(font
				(size 1.27 1.27)
			)
			(justify left bottom)
		)
	)
	(label "DDR.A6"
		(at 95.25 66.04 0)
		(effects
			(font
				(size 1.27 1.27)
			)
			(justify left bottom)
		)
	)
	(label "DDR.~{RAS}"
		(at 194.31 91.44 0)
		(effects
			(font
				(size 1.27 1.27)
			)
			(justify left bottom)
		)
	)
	(label "DDR.~{CAS}"
		(at 148.59 96.52 0)
		(effects
			(font
				(size 1.27 1.27)
			)
			(justify left bottom)
		)
	)
	(label "SRAM.A3"
		(at 99.06 207.01 0)
		(effects
			(font
				(size 1.27 1.27)
			)
			(justify left bottom)
		)
	)
	(label "SRAM.DQ6"
		(at 140.97 222.25 0)
		(effects
			(font
				(size 1.27 1.27)
			)
			(justify left bottom)
		)
	)
	(label "SRAM.DQ1"
		(at 140.97 209.55 0)
		(effects
			(font
				(size 1.27 1.27)
			)
			(justify left bottom)
		)
	)
	(label "DDR.A1"
		(at 95.25 53.34 0)
		(effects
			(font
				(size 1.27 1.27)
			)
			(justify left bottom)
		)
	)
	(label "SRAM.A1"
		(at 99.06 201.93 0)
		(effects
			(font
				(size 1.27 1.27)
			)
			(justify left bottom)
		)
	)
	(label "DDR.~{RAS}"
		(at 148.59 99.06 0)
		(effects
			(font
				(size 1.27 1.27)
			)
			(justify left bottom)
		)
	)
	(label "DDR.ODT"
		(at 95.25 111.76 0)
		(effects
			(font
				(size 1.27 1.27)
			)
			(justify left bottom)
		)
	)
	(label "DDR.DQ1"
		(at 149.86 63.5 0)
		(effects
			(font
				(size 1.27 1.27)
			)
			(justify left bottom)
		)
	)
	(label "DDR.A5"
		(at 95.25 63.5 0)
		(effects
			(font
				(size 1.27 1.27)
			)
			(justify left bottom)
		)
	)
	(label "SRAM.DQ3"
		(at 140.97 214.63 0)
		(effects
			(font
				(size 1.27 1.27)
			)
			(justify left bottom)
		)
	)
	(label "DDR.DQ6"
		(at 149.86 76.2 0)
		(effects
			(font
				(size 1.27 1.27)
			)
			(justify left bottom)
		)
	)
	(hierarchical_label "DDR{DDR3_DRAM}"
		(shape input)
		(at 78.74 121.92 180)
		(effects
			(font
				(size 1.27 1.27)
			)
			(justify right)
		)
	)
	(hierarchical_label "SRAM{SRAM}"
		(shape input)
		(at 78.74 257.81 180)
		(effects
			(font
				(size 1.27 1.27)
			)
			(justify right)
		)
	)
	(symbol
		(lib_id "antmicroCapacitors0402:C_100n_0402")
		(at 257.81 33.02 90)
		(unit 1)
		(exclude_from_sim no)
		(in_bom yes)
		(on_board yes)
		(dnp no)
		(property "Reference" "C392"
			(at 258.445 28.575 90)
			(effects
				(font
					(size 1.27 1.27)
				)
				(justify right)
			)
		)
		(property "Value" "C_100n_0402"
			(at 267.97 12.7 0)
			(effects
				(font
					(size 1.27 1.27)
					(thickness 0.15)
				)
				(justify left bottom)
				(hide yes)
			)
		)
		(property "Footprint" "antmicro-footprints:C_0402_1005Metric"
			(at 270.51 12.7 0)
			(effects
				(font
					(size 1.27 1.27)
					(thickness 0.15)
				)
				(justify left bottom)
				(hide yes)
			)
		)
		(property "Datasheet" "https://www.murata.com/products/productdetail?partno=GRM155R61H104KE14%23"
			(at 273.05 12.7 0)
			(effects
				(font
					(size 1.27 1.27)
					(thickness 0.15)
				)
				(justify left bottom)
				(hide yes)
			)
		)
		(property "Description" ""
			(at 257.81 33.02 0)
			(effects
				(font
					(size 1.27 1.27)
				)
			)
		)
		(property "Manufacturer" "Murata"
			(at 278.13 12.7 0)
			(effects
				(font
					(size 1.27 1.27)
					(thickness 0.15)
				)
				(justify left bottom)
				(hide yes)
			)
		)
		(property "MPN" "GRM155R61H104KE14D"
			(at 275.59 12.7 0)
			(effects
				(font
					(size 1.27 1.27)
					(thickness 0.15)
				)
				(justify left bottom)
				(hide yes)
			)
		)
		(property "Val" "100n"
			(at 258.445 32.385 90)
			(effects
				(font
					(size 1.27 1.27)
					(thickness 0.15)
				)
				(justify right)
			)
		)
		(property "License" "Apache-2.0"
			(at 280.67 12.7 0)
			(effects
				(font
					(size 1.27 1.27)
					(thickness 0.15)
				)
				(justify left bottom)
				(hide yes)
			)
		)
		(property "Author" "Antmicro"
			(at 283.21 12.7 0)
			(effects
				(font
					(size 1.27 1.27)
					(thickness 0.15)
				)
				(justify left bottom)
				(hide yes)
			)
		)
		(property "Voltage" "50V"
			(at 285.75 12.7 0)
			(effects
				(font
					(size 1.27 1.27)
				)
				(justify left bottom)
				(hide yes)
			)
		)
		(property "Dielectric" "X5R"
			(at 288.29 12.7 0)
			(effects
				(font
					(size 1.27 1.27)
				)
				(justify left bottom)
				(hide yes)
			)
		)
		(pin "1"
		)
		(pin "2"
		)
		(instances
			(project "k410t-devboard"
				(path ""
					(reference "C392")
					(unit 1)
				)
			)
		)
	)
	(symbol
		(lib_id "antmicroCapacitors0402:C_10u_0402")
		(at 320.04 59.69 90)
		(unit 1)
		(exclude_from_sim no)
		(in_bom yes)
		(on_board yes)
		(dnp no)
		(property "Reference" "C169"
			(at 320.675 55.245 90)
			(effects
				(font
					(size 1.27 1.27)
				)
				(justify right)
			)
		)
		(property "Value" "C_10u_0402"
			(at 330.2 39.37 0)
			(effects
				(font
					(size 1.27 1.27)
					(thickness 0.15)
				)
				(justify left bottom)
				(hide yes)
			)
		)
		(property "Footprint" "antmicro-footprints:C_0402_1005Metric"
			(at 332.74 39.37 0)
			(effects
				(font
					(size 1.27 1.27)
					(thickness 0.15)
				)
				(justify left bottom)
				(hide yes)
			)
		)
		(property "Datasheet" "https://www.yageo.com/en/Chart/Download/pdf/CC0402MRX5R5BB106"
			(at 335.28 39.37 0)
			(effects
				(font
					(size 1.27 1.27)
					(thickness 0.15)
				)
				(justify left bottom)
				(hide yes)
			)
		)
		(property "Description" ""
			(at 320.04 59.69 0)
			(effects
				(font
					(size 1.27 1.27)
				)
			)
		)
		(property "Manufacturer" "YAGEO"
			(at 340.36 39.37 0)
			(effects
				(font
					(size 1.27 1.27)
					(thickness 0.15)
				)
				(justify left bottom)
				(hide yes)
			)
		)
		(property "MPN" "CC0402MRX5R5BB106"
			(at 337.82 39.37 0)
			(effects
				(font
					(size 1.27 1.27)
					(thickness 0.15)
				)
				(justify left bottom)
				(hide yes)
			)
		)
		(property "Val" "10u"
			(at 320.675 59.055 90)
			(effects
				(font
					(size 1.27 1.27)
					(thickness 0.15)
				)
				(justify right)
			)
		)
		(property "License" "Apache-2.0"
			(at 342.9 39.37 0)
			(effects
				(font
					(size 1.27 1.27)
					(thickness 0.15)
				)
				(justify left bottom)
				(hide yes)
			)
		)
		(property "Author" "Antmicro"
			(at 345.44 39.37 0)
			(effects
				(font
					(size 1.27 1.27)
					(thickness 0.15)
				)
				(justify left bottom)
				(hide yes)
			)
		)
		(property "Voltage" ""
			(at 347.98 39.37 0)
			(effects
				(font
					(size 1.27 1.27)
				)
				(justify left bottom)
				(hide yes)
			)
		)
		(property "Dielectric" ""
			(at 350.52 39.37 0)
			(effects
				(font
					(size 1.27 1.27)
				)
				(justify left bottom)
				(hide yes)
			)
		)
		(pin "1"
		)
		(pin "2"
		)
		(instances
			(project "k410t-devboard"
				(path ""
					(reference "C169")
					(unit 1)
				)
			)
		)
	)
	(symbol
		(lib_id "antmicroCapacitors0402:C_100n_0402")
		(at 334.01 59.69 90)
		(unit 1)
		(exclude_from_sim no)
		(in_bom yes)
		(on_board yes)
		(dnp no)
		(property "Reference" "C171"
			(at 334.645 55.245 90)
			(effects
				(font
					(size 1.27 1.27)
				)
				(justify right)
			)
		)
		(property "Value" "C_100n_0402"
			(at 344.17 39.37 0)
			(effects
				(font
					(size 1.27 1.27)
					(thickness 0.15)
				)
				(justify left bottom)
				(hide yes)
			)
		)
		(property "Footprint" "antmicro-footprints:C_0402_1005Metric"
			(at 346.71 39.37 0)
			(effects
				(font
					(size 1.27 1.27)
					(thickness 0.15)
				)
				(justify left bottom)
				(hide yes)
			)
		)
		(property "Datasheet" "https://www.murata.com/products/productdetail?partno=GRM155R61H104KE14%23"
			(at 349.25 39.37 0)
			(effects
				(font
					(size 1.27 1.27)
					(thickness 0.15)
				)
				(justify left bottom)
				(hide yes)
			)
		)
		(property "Description" ""
			(at 334.01 59.69 0)
			(effects
				(font
					(size 1.27 1.27)
				)
			)
		)
		(property "Manufacturer" "Murata"
			(at 354.33 39.37 0)
			(effects
				(font
					(size 1.27 1.27)
					(thickness 0.15)
				)
				(justify left bottom)
				(hide yes)
			)
		)
		(property "MPN" "GRM155R61H104KE14D"
			(at 351.79 39.37 0)
			(effects
				(font
					(size 1.27 1.27)
					(thickness 0.15)
				)
				(justify left bottom)
				(hide yes)
			)
		)
		(property "Val" "100n"
			(at 334.645 59.055 90)
			(effects
				(font
					(size 1.27 1.27)
					(thickness 0.15)
				)
				(justify right)
			)
		)
		(property "License" "Apache-2.0"
			(at 356.87 39.37 0)
			(effects
				(font
					(size 1.27 1.27)
					(thickness 0.15)
				)
				(justify left bottom)
				(hide yes)
			)
		)
		(property "Author" "Antmicro"
			(at 359.41 39.37 0)
			(effects
				(font
					(size 1.27 1.27)
					(thickness 0.15)
				)
				(justify left bottom)
				(hide yes)
			)
		)
		(property "Voltage" "50V"
			(at 361.95 39.37 0)
			(effects
				(font
					(size 1.27 1.27)
				)
				(justify left bottom)
				(hide yes)
			)
		)
		(property "Dielectric" "X5R"
			(at 364.49 39.37 0)
			(effects
				(font
					(size 1.27 1.27)
				)
				(justify left bottom)
				(hide yes)
			)
		)
		(pin "1"
		)
		(pin "2"
		)
		(instances
			(project "k410t-devboard"
				(path ""
					(reference "C171")
					(unit 1)
				)
			)
		)
	)
	(symbol
		(lib_id "antmicroCapacitors0402:C_10u_0402")
		(at 320.04 50.8 90)
		(unit 1)
		(exclude_from_sim no)
		(in_bom yes)
		(on_board yes)
		(dnp no)
		(property "Reference" "C168"
			(at 320.675 46.355 90)
			(effects
				(font
					(size 1.27 1.27)
				)
				(justify right)
			)
		)
		(property "Value" "C_10u_0402"
			(at 330.2 30.48 0)
			(effects
				(font
					(size 1.27 1.27)
					(thickness 0.15)
				)
				(justify left bottom)
				(hide yes)
			)
		)
		(property "Footprint" "antmicro-footprints:C_0402_1005Metric"
			(at 332.74 30.48 0)
			(effects
				(font
					(size 1.27 1.27)
					(thickness 0.15)
				)
				(justify left bottom)
				(hide yes)
			)
		)
		(property "Datasheet" "https://www.yageo.com/en/Chart/Download/pdf/CC0402MRX5R5BB106"
			(at 335.28 30.48 0)
			(effects
				(font
					(size 1.27 1.27)
					(thickness 0.15)
				)
				(justify left bottom)
				(hide yes)
			)
		)
		(property "Description" ""
			(at 320.04 50.8 0)
			(effects
				(font
					(size 1.27 1.27)
				)
			)
		)
		(property "Manufacturer" "YAGEO"
			(at 340.36 30.48 0)
			(effects
				(font
					(size 1.27 1.27)
					(thickness 0.15)
				)
				(justify left bottom)
				(hide yes)
			)
		)
		(property "MPN" "CC0402MRX5R5BB106"
			(at 337.82 30.48 0)
			(effects
				(font
					(size 1.27 1.27)
					(thickness 0.15)
				)
				(justify left bottom)
				(hide yes)
			)
		)
		(property "Val" "10u"
			(at 320.675 50.165 90)
			(effects
				(font
					(size 1.27 1.27)
					(thickness 0.15)
				)
				(justify right)
			)
		)
		(property "License" "Apache-2.0"
			(at 342.9 30.48 0)
			(effects
				(font
					(size 1.27 1.27)
					(thickness 0.15)
				)
				(justify left bottom)
				(hide yes)
			)
		)
		(property "Author" "Antmicro"
			(at 345.44 30.48 0)
			(effects
				(font
					(size 1.27 1.27)
					(thickness 0.15)
				)
				(justify left bottom)
				(hide yes)
			)
		)
		(property "Voltage" ""
			(at 347.98 30.48 0)
			(effects
				(font
					(size 1.27 1.27)
				)
				(justify left bottom)
				(hide yes)
			)
		)
		(property "Dielectric" ""
			(at 350.52 30.48 0)
			(effects
				(font
					(size 1.27 1.27)
				)
				(justify left bottom)
				(hide yes)
			)
		)
		(pin "1"
		)
		(pin "2"
		)
		(instances
			(project "k410t-devboard"
				(path ""
					(reference "C168")
					(unit 1)
				)
			)
		)
	)
	(symbol
		(lib_id "antmicroCapacitors0402:C_100n_0402")
		(at 205.74 33.02 90)
		(unit 1)
		(exclude_from_sim no)
		(in_bom yes)
		(on_board yes)
		(dnp no)
		(property "Reference" "C187"
			(at 206.375 28.575 90)
			(effects
				(font
					(size 1.27 1.27)
				)
				(justify right)
			)
		)
		(property "Value" "C_100n_0402"
			(at 215.9 12.7 0)
			(effects
				(font
					(size 1.27 1.27)
					(thickness 0.15)
				)
				(justify left bottom)
				(hide yes)
			)
		)
		(property "Footprint" "antmicro-footprints:C_0402_1005Metric"
			(at 218.44 12.7 0)
			(effects
				(font
					(size 1.27 1.27)
					(thickness 0.15)
				)
				(justify left bottom)
				(hide yes)
			)
		)
		(property "Datasheet" "https://www.murata.com/products/productdetail?partno=GRM155R61H104KE14%23"
			(at 220.98 12.7 0)
			(effects
				(font
					(size 1.27 1.27)
					(thickness 0.15)
				)
				(justify left bottom)
				(hide yes)
			)
		)
		(property "Description" ""
			(at 205.74 33.02 0)
			(effects
				(font
					(size 1.27 1.27)
				)
			)
		)
		(property "Manufacturer" "Murata"
			(at 226.06 12.7 0)
			(effects
				(font
					(size 1.27 1.27)
					(thickness 0.15)
				)
				(justify left bottom)
				(hide yes)
			)
		)
		(property "MPN" "GRM155R61H104KE14D"
			(at 223.52 12.7 0)
			(effects
				(font
					(size 1.27 1.27)
					(thickness 0.15)
				)
				(justify left bottom)
				(hide yes)
			)
		)
		(property "Val" "100n"
			(at 206.375 32.385 90)
			(effects
				(font
					(size 1.27 1.27)
					(thickness 0.15)
				)
				(justify right)
			)
		)
		(property "License" "Apache-2.0"
			(at 228.6 12.7 0)
			(effects
				(font
					(size 1.27 1.27)
					(thickness 0.15)
				)
				(justify left bottom)
				(hide yes)
			)
		)
		(property "Author" "Antmicro"
			(at 231.14 12.7 0)
			(effects
				(font
					(size 1.27 1.27)
					(thickness 0.15)
				)
				(justify left bottom)
				(hide yes)
			)
		)
		(property "Voltage" "50V"
			(at 233.68 12.7 0)
			(effects
				(font
					(size 1.27 1.27)
				)
				(justify left bottom)
				(hide yes)
			)
		)
		(property "Dielectric" "X5R"
			(at 236.22 12.7 0)
			(effects
				(font
					(size 1.27 1.27)
				)
				(justify left bottom)
				(hide yes)
			)
		)
		(pin "1"
		)
		(pin "2"
		)
		(instances
			(project "k410t-devboard"
				(path ""
					(reference "C187")
					(unit 1)
				)
			)
		)
	)
	(symbol
		(lib_id "antmicroCapacitors0402:C_100n_0402")
		(at 342.9 50.8 90)
		(unit 1)
		(exclude_from_sim no)
		(in_bom yes)
		(on_board yes)
		(dnp no)
		(property "Reference" "C172"
			(at 343.535 46.355 90)
			(effects
				(font
					(size 1.27 1.27)
				)
				(justify right)
			)
		)
		(property "Value" "C_100n_0402"
			(at 353.06 30.48 0)
			(effects
				(font
					(size 1.27 1.27)
					(thickness 0.15)
				)
				(justify left bottom)
				(hide yes)
			)
		)
		(property "Footprint" "antmicro-footprints:C_0402_1005Metric"
			(at 355.6 30.48 0)
			(effects
				(font
					(size 1.27 1.27)
					(thickness 0.15)
				)
				(justify left bottom)
				(hide yes)
			)
		)
		(property "Datasheet" "https://www.murata.com/products/productdetail?partno=GRM155R61H104KE14%23"
			(at 358.14 30.48 0)
			(effects
				(font
					(size 1.27 1.27)
					(thickness 0.15)
				)
				(justify left bottom)
				(hide yes)
			)
		)
		(property "Description" ""
			(at 342.9 50.8 0)
			(effects
				(font
					(size 1.27 1.27)
				)
			)
		)
		(property "Manufacturer" "Murata"
			(at 363.22 30.48 0)
			(effects
				(font
					(size 1.27 1.27)
					(thickness 0.15)
				)
				(justify left bottom)
				(hide yes)
			)
		)
		(property "MPN" "GRM155R61H104KE14D"
			(at 360.68 30.48 0)
			(effects
				(font
					(size 1.27 1.27)
					(thickness 0.15)
				)
				(justify left bottom)
				(hide yes)
			)
		)
		(property "Val" "100n"
			(at 343.535 50.165 90)
			(effects
				(font
					(size 1.27 1.27)
					(thickness 0.15)
				)
				(justify right)
			)
		)
		(property "License" "Apache-2.0"
			(at 365.76 30.48 0)
			(effects
				(font
					(size 1.27 1.27)
					(thickness 0.15)
				)
				(justify left bottom)
				(hide yes)
			)
		)
		(property "Author" "Antmicro"
			(at 368.3 30.48 0)
			(effects
				(font
					(size 1.27 1.27)
					(thickness 0.15)
				)
				(justify left bottom)
				(hide yes)
			)
		)
		(property "Voltage" "50V"
			(at 370.84 30.48 0)
			(effects
				(font
					(size 1.27 1.27)
				)
				(justify left bottom)
				(hide yes)
			)
		)
		(property "Dielectric" "X5R"
			(at 373.38 30.48 0)
			(effects
				(font
					(size 1.27 1.27)
				)
				(justify left bottom)
				(hide yes)
			)
		)
		(pin "1"
		)
		(pin "2"
		)
		(instances
			(project "k410t-devboard"
				(path ""
					(reference "C172")
					(unit 1)
				)
			)
		)
	)
	(symbol
		(lib_id "antmicroCapacitors0603:C_47u_0603")
		(at 311.15 59.69 90)
		(unit 1)
		(exclude_from_sim no)
		(in_bom yes)
		(on_board yes)
		(dnp no)
		(property "Reference" "C167"
			(at 316.865 55.245 90)
			(effects
				(font
					(size 1.27 1.27)
				)
				(justify left)
			)
		)
		(property "Value" "C_47u_0603"
			(at 321.31 39.37 0)
			(effects
				(font
					(size 1.27 1.27)
					(thickness 0.15)
				)
				(justify left bottom)
				(hide yes)
			)
		)
		(property "Footprint" "antmicro-footprints:C_0603_1608Metric"
			(at 323.85 39.37 0)
			(effects
				(font
					(size 1.27 1.27)
					(thickness 0.15)
				)
				(justify left bottom)
				(hide yes)
			)
		)
		(property "Datasheet" "https://www.murata.com/products/productdetail?partno=GRM188R60J476ME15%23"
			(at 326.39 39.37 0)
			(effects
				(font
					(size 1.27 1.27)
					(thickness 0.15)
				)
				(justify left bottom)
				(hide yes)
			)
		)
		(property "Description" ""
			(at 311.15 59.69 0)
			(effects
				(font
					(size 1.27 1.27)
				)
			)
		)
		(property "Manufacturer" "Murata"
			(at 331.47 39.37 0)
			(effects
				(font
					(size 1.27 1.27)
					(thickness 0.15)
				)
				(justify left bottom)
				(hide yes)
			)
		)
		(property "MPN" "GRM188R60J476ME15D"
			(at 328.93 39.37 0)
			(effects
				(font
					(size 1.27 1.27)
					(thickness 0.15)
				)
				(justify left bottom)
				(hide yes)
			)
		)
		(property "Val" "47u"
			(at 315.595 59.055 90)
			(effects
				(font
					(size 1.27 1.27)
					(thickness 0.15)
				)
				(justify left)
			)
		)
		(property "License" "Apache-2.0"
			(at 334.01 39.37 0)
			(effects
				(font
					(size 1.27 1.27)
					(thickness 0.15)
				)
				(justify left bottom)
				(hide yes)
			)
		)
		(property "Author" "Antmicro"
			(at 336.55 39.37 0)
			(effects
				(font
					(size 1.27 1.27)
					(thickness 0.15)
				)
				(justify left bottom)
				(hide yes)
			)
		)
		(property "Voltage" ""
			(at 339.09 39.37 0)
			(effects
				(font
					(size 1.27 1.27)
				)
				(justify left bottom)
				(hide yes)
			)
		)
		(property "Dielectric" ""
			(at 341.63 39.37 0)
			(effects
				(font
					(size 1.27 1.27)
				)
				(justify left bottom)
				(hide yes)
			)
		)
		(pin "1"
		)
		(pin "2"
		)
		(instances
			(project "k410t-devboard"
				(path ""
					(reference "C167")
					(unit 1)
				)
			)
		)
	)
	(symbol
		(lib_id "antmicropower:GND")
		(at 146.05 193.04 0)
		(unit 1)
		(exclude_from_sim no)
		(in_bom yes)
		(on_board yes)
		(dnp no)
		(property "Reference" "#PWR060"
			(at 146.05 199.39 0)
			(effects
				(font
					(size 1.27 1.27)
				)
				(hide yes)
			)
		)
		(property "Value" "GND"
			(at 146.05 196.85 0)
			(effects
				(font
					(size 1.27 1.27)
				)
			)
		)
		(property "Footprint" ""
			(at 154.94 200.66 0)
			(effects
				(font
					(size 1.27 1.27)
					(thickness 0.15)
				)
				(justify left bottom)
				(hide yes)
			)
		)
		(property "Datasheet" ""
			(at 154.94 205.74 0)
			(effects
				(font
					(size 1.27 1.27)
					(thickness 0.15)
				)
				(justify left bottom)
				(hide yes)
			)
		)
		(property "Description" ""
			(at 146.05 193.04 0)
			(effects
				(font
					(size 1.27 1.27)
				)
			)
		)
		(property "Author" "Antmicro"
			(at 154.94 200.66 0)
			(effects
				(font
					(size 1.27 1.27)
					(thickness 0.15)
				)
				(justify left bottom)
				(hide yes)
			)
		)
		(property "License" "Apache-2.0"
			(at 154.94 203.2 0)
			(effects
				(font
					(size 1.27 1.27)
					(thickness 0.15)
				)
				(justify left bottom)
				(hide yes)
			)
		)
		(pin "1"
		)
		(instances
			(project "k410t-devboard"
				(path ""
					(reference "#PWR060")
					(unit 1)
				)
			)
		)
	)
	(symbol
		(lib_id "antmicropower:+1V35")
		(at 307.34 24.13 0)
		(unit 1)
		(exclude_from_sim no)
		(in_bom yes)
		(on_board yes)
		(dnp no)
		(fields_autoplaced yes)
		(property "Reference" "#PWR085"
			(at 307.34 27.94 0)
			(effects
				(font
					(size 1.27 1.27)
				)
				(hide yes)
			)
		)
		(property "Value" "+1V35"
			(at 307.34 20.574 0)
			(effects
				(font
					(size 1.27 1.27)
				)
			)
		)
		(property "Footprint" ""
			(at 307.34 24.13 0)
			(effects
				(font
					(size 1.27 1.27)
				)
				(hide yes)
			)
		)
		(property "Datasheet" ""
			(at 307.34 24.13 0)
			(effects
				(font
					(size 1.27 1.27)
				)
				(hide yes)
			)
		)
		(property "Description" ""
			(at 307.34 24.13 0)
			(effects
				(font
					(size 1.27 1.27)
				)
			)
		)
		(pin "1"
		)
		(instances
			(project "k410t-devboard"
				(path ""
					(reference "#PWR085")
					(unit 1)
				)
			)
		)
	)
	(symbol
		(lib_id "antmicroResistorNetworksArrays:4x39R_0201_array")
		(at 308.61 87.63 0)
		(unit 1)
		(exclude_from_sim no)
		(in_bom yes)
		(on_board yes)
		(dnp no)
		(fields_autoplaced yes)
		(property "Reference" "R14"
			(at 313.69 80.645 0)
			(effects
				(font
					(size 1.27 1.27)
				)
			)
		)
		(property "Value" "4x39R_0201_array"
			(at 335.28 93.345 0)
			(effects
				(font
					(size 1.27 1.27)
					(thickness 0.15)
				)
				(justify left bottom)
				(hide yes)
			)
		)
		(property "Footprint" "antmicro-footprints:R_Array_4x0201_Panasonic_EXB18V"
			(at 335.28 98.425 0)
			(effects
				(font
					(size 1.27 1.27)
					(thickness 0.15)
				)
				(justify left bottom)
				(hide yes)
			)
		)
		(property "Datasheet" "https://eu.mouser.com/datasheet/2/315/AOC0000C14-1108062.pdf"
			(at 335.28 100.965 0)
			(effects
				(font
					(size 1.27 1.27)
					(thickness 0.15)
				)
				(justify left bottom)
				(hide yes)
			)
		)
		(property "Description" ""
			(at 308.61 87.63 0)
			(effects
				(font
					(size 1.27 1.27)
				)
			)
		)
		(property "MPN" "EXB-18V390JX"
			(at 335.28 103.505 0)
			(effects
				(font
					(size 1.27 1.27)
					(thickness 0.15)
				)
				(justify left bottom)
				(hide yes)
			)
		)
		(property "Manufacturer" "Panasonic"
			(at 335.28 106.045 0)
			(effects
				(font
					(size 1.27 1.27)
					(thickness 0.15)
				)
				(justify left bottom)
				(hide yes)
			)
		)
		(property "Author" "Antmicro"
			(at 335.28 108.585 0)
			(effects
				(font
					(size 1.27 1.27)
					(thickness 0.15)
				)
				(justify left bottom)
				(hide yes)
			)
		)
		(property "License" "Apache-2.0"
			(at 335.28 111.125 0)
			(effects
				(font
					(size 1.27 1.27)
					(thickness 0.15)
				)
				(justify left bottom)
				(hide yes)
			)
		)
		(property "Val" "4x39R_0201"
			(at 313.69 83.185 0)
			(effects
				(font
					(size 1.27 1.27)
				)
			)
		)
		(pin "1"
		)
		(pin "2"
		)
		(pin "3"
		)
		(pin "4"
		)
		(pin "5"
		)
		(pin "6"
		)
		(pin "7"
		)
		(pin "8"
		)
		(instances
			(project "k410t-devboard"
				(path ""
					(reference "R14")
					(unit 1)
				)
			)
		)
	)
	(symbol
		(lib_id "antmicropower:+0V675_VTT")
		(at 224.79 86.36 0)
		(unit 1)
		(exclude_from_sim no)
		(in_bom yes)
		(on_board yes)
		(dnp no)
		(fields_autoplaced yes)
		(property "Reference" "#PWR0283"
			(at 224.79 90.17 0)
			(effects
				(font
					(size 1.27 1.27)
				)
				(hide yes)
			)
		)
		(property "Value" "+0V675_VTT"
			(at 224.79 82.804 0)
			(effects
				(font
					(size 1.27 1.27)
				)
			)
		)
		(property "Footprint" ""
			(at 224.79 86.36 0)
			(effects
				(font
					(size 1.27 1.27)
				)
				(hide yes)
			)
		)
		(property "Datasheet" ""
			(at 224.79 86.36 0)
			(effects
				(font
					(size 1.27 1.27)
				)
				(hide yes)
			)
		)
		(property "Description" ""
			(at 224.79 86.36 0)
			(effects
				(font
					(size 1.27 1.27)
				)
			)
		)
		(pin "1"
		)
		(instances
			(project "k410t-devboard"
				(path ""
					(reference "#PWR0283")
					(unit 1)
				)
			)
		)
	)
	(symbol
		(lib_id "antmicropower:GND")
		(at 232.41 35.56 0)
		(unit 1)
		(exclude_from_sim no)
		(in_bom yes)
		(on_board yes)
		(dnp no)
		(property "Reference" "#PWR079"
			(at 232.41 41.91 0)
			(effects
				(font
					(size 1.27 1.27)
				)
				(hide yes)
			)
		)
		(property "Value" "GND"
			(at 232.41 39.37 0)
			(effects
				(font
					(size 1.27 1.27)
				)
			)
		)
		(property "Footprint" ""
			(at 241.3 43.18 0)
			(effects
				(font
					(size 1.27 1.27)
					(thickness 0.15)
				)
				(justify left bottom)
				(hide yes)
			)
		)
		(property "Datasheet" ""
			(at 241.3 48.26 0)
			(effects
				(font
					(size 1.27 1.27)
					(thickness 0.15)
				)
				(justify left bottom)
				(hide yes)
			)
		)
		(property "Description" ""
			(at 232.41 35.56 0)
			(effects
				(font
					(size 1.27 1.27)
				)
			)
		)
		(property "Author" "Antmicro"
			(at 241.3 43.18 0)
			(effects
				(font
					(size 1.27 1.27)
					(thickness 0.15)
				)
				(justify left bottom)
				(hide yes)
			)
		)
		(property "License" "Apache-2.0"
			(at 241.3 45.72 0)
			(effects
				(font
					(size 1.27 1.27)
					(thickness 0.15)
				)
				(justify left bottom)
				(hide yes)
			)
		)
		(pin "1"
		)
		(instances
			(project "k410t-devboard"
				(path ""
					(reference "#PWR079")
					(unit 1)
				)
			)
		)
	)
	(symbol
		(lib_id "antmicroCapacitors0402:C_10u_0402")
		(at 275.59 33.02 90)
		(unit 1)
		(exclude_from_sim no)
		(in_bom yes)
		(on_board yes)
		(dnp no)
		(property "Reference" "C189"
			(at 276.225 28.575 90)
			(effects
				(font
					(size 1.27 1.27)
				)
				(justify right)
			)
		)
		(property "Value" "C_10u_0402"
			(at 285.75 12.7 0)
			(effects
				(font
					(size 1.27 1.27)
					(thickness 0.15)
				)
				(justify left bottom)
				(hide yes)
			)
		)
		(property "Footprint" "antmicro-footprints:C_0402_1005Metric"
			(at 288.29 12.7 0)
			(effects
				(font
					(size 1.27 1.27)
					(thickness 0.15)
				)
				(justify left bottom)
				(hide yes)
			)
		)
		(property "Datasheet" "https://www.yageo.com/en/Chart/Download/pdf/CC0402MRX5R5BB106"
			(at 290.83 12.7 0)
			(effects
				(font
					(size 1.27 1.27)
					(thickness 0.15)
				)
				(justify left bottom)
				(hide yes)
			)
		)
		(property "Description" ""
			(at 275.59 33.02 0)
			(effects
				(font
					(size 1.27 1.27)
				)
			)
		)
		(property "Manufacturer" "YAGEO"
			(at 295.91 12.7 0)
			(effects
				(font
					(size 1.27 1.27)
					(thickness 0.15)
				)
				(justify left bottom)
				(hide yes)
			)
		)
		(property "MPN" "CC0402MRX5R5BB106"
			(at 293.37 12.7 0)
			(effects
				(font
					(size 1.27 1.27)
					(thickness 0.15)
				)
				(justify left bottom)
				(hide yes)
			)
		)
		(property "Val" "10u"
			(at 276.225 32.385 90)
			(effects
				(font
					(size 1.27 1.27)
					(thickness 0.15)
				)
				(justify right)
			)
		)
		(property "License" "Apache-2.0"
			(at 298.45 12.7 0)
			(effects
				(font
					(size 1.27 1.27)
					(thickness 0.15)
				)
				(justify left bottom)
				(hide yes)
			)
		)
		(property "Author" "Antmicro"
			(at 300.99 12.7 0)
			(effects
				(font
					(size 1.27 1.27)
					(thickness 0.15)
				)
				(justify left bottom)
				(hide yes)
			)
		)
		(property "Voltage" ""
			(at 303.53 12.7 0)
			(effects
				(font
					(size 1.27 1.27)
				)
				(justify left bottom)
				(hide yes)
			)
		)
		(property "Dielectric" ""
			(at 306.07 12.7 0)
			(effects
				(font
					(size 1.27 1.27)
				)
				(justify left bottom)
				(hide yes)
			)
		)
		(pin "1"
		)
		(pin "2"
		)
		(instances
			(project "k410t-devboard"
				(path ""
					(reference "C189")
					(unit 1)
				)
			)
		)
	)
	(symbol
		(lib_id "antmicroCapacitors0402:C_100n_0402")
		(at 241.3 33.02 90)
		(unit 1)
		(exclude_from_sim no)
		(in_bom yes)
		(on_board yes)
		(dnp no)
		(property "Reference" "C390"
			(at 241.935 28.575 90)
			(effects
				(font
					(size 1.27 1.27)
				)
				(justify right)
			)
		)
		(property "Value" "C_100n_0402"
			(at 251.46 12.7 0)
			(effects
				(font
					(size 1.27 1.27)
					(thickness 0.15)
				)
				(justify left bottom)
				(hide yes)
			)
		)
		(property "Footprint" "antmicro-footprints:C_0402_1005Metric"
			(at 254 12.7 0)
			(effects
				(font
					(size 1.27 1.27)
					(thickness 0.15)
				)
				(justify left bottom)
				(hide yes)
			)
		)
		(property "Datasheet" "https://www.murata.com/products/productdetail?partno=GRM155R61H104KE14%23"
			(at 256.54 12.7 0)
			(effects
				(font
					(size 1.27 1.27)
					(thickness 0.15)
				)
				(justify left bottom)
				(hide yes)
			)
		)
		(property "Description" ""
			(at 241.3 33.02 0)
			(effects
				(font
					(size 1.27 1.27)
				)
			)
		)
		(property "Manufacturer" "Murata"
			(at 261.62 12.7 0)
			(effects
				(font
					(size 1.27 1.27)
					(thickness 0.15)
				)
				(justify left bottom)
				(hide yes)
			)
		)
		(property "MPN" "GRM155R61H104KE14D"
			(at 259.08 12.7 0)
			(effects
				(font
					(size 1.27 1.27)
					(thickness 0.15)
				)
				(justify left bottom)
				(hide yes)
			)
		)
		(property "Val" "100n"
			(at 241.935 32.385 90)
			(effects
				(font
					(size 1.27 1.27)
					(thickness 0.15)
				)
				(justify right)
			)
		)
		(property "License" "Apache-2.0"
			(at 264.16 12.7 0)
			(effects
				(font
					(size 1.27 1.27)
					(thickness 0.15)
				)
				(justify left bottom)
				(hide yes)
			)
		)
		(property "Author" "Antmicro"
			(at 266.7 12.7 0)
			(effects
				(font
					(size 1.27 1.27)
					(thickness 0.15)
				)
				(justify left bottom)
				(hide yes)
			)
		)
		(property "Voltage" "50V"
			(at 269.24 12.7 0)
			(effects
				(font
					(size 1.27 1.27)
				)
				(justify left bottom)
				(hide yes)
			)
		)
		(property "Dielectric" "X5R"
			(at 271.78 12.7 0)
			(effects
				(font
					(size 1.27 1.27)
				)
				(justify left bottom)
				(hide yes)
			)
		)
		(pin "1"
		)
		(pin "2"
		)
		(instances
			(project "k410t-devboard"
				(path ""
					(reference "C390")
					(unit 1)
				)
			)
		)
	)
	(symbol
		(lib_id "antmicroMemory:MT41K512M8DA")
		(at 111.76 48.26 0)
		(unit 1)
		(exclude_from_sim no)
		(in_bom yes)
		(on_board yes)
		(dnp no)
		(fields_autoplaced yes)
		(property "Reference" "U5"
			(at 127 39.37 0)
			(effects
				(font
					(size 1.27 1.27)
				)
			)
		)
		(property "Value" "MT41K512M8DA"
			(at 127 41.91 0)
			(effects
				(font
					(size 1.27 1.27)
					(thickness 0.15)
				)
				(hide yes)
			)
		)
		(property "Footprint" "antmicro-footprints:Micron_FBGA-78"
			(at 157.48 55.88 0)
			(effects
				(font
					(size 1.27 1.27)
					(thickness 0.15)
				)
				(justify left bottom)
				(hide yes)
			)
		)
		(property "Datasheet" "https://media-www.micron.com/-/media/client/global/documents/products/data-sheet/dram/ddr3/4gb_1_35v_ddr3l_xit_addendum.pdf?rev=7a72ef4abde14a46b61107e1a0bb1af6"
			(at 157.48 58.42 0)
			(effects
				(font
					(size 1.27 1.27)
					(thickness 0.15)
				)
				(justify left bottom)
				(hide yes)
			)
		)
		(property "Description" ""
			(at 111.76 48.26 0)
			(effects
				(font
					(size 1.27 1.27)
				)
			)
		)
		(property "Manufacturer" "Micron Technology"
			(at 157.48 60.96 0)
			(effects
				(font
					(size 1.27 1.27)
					(thickness 0.15)
				)
				(justify left bottom)
				(hide yes)
			)
		)
		(property "MPN" "MT41K512M8DA-107 XIT:P TR"
			(at 127 41.91 0)
			(effects
				(font
					(size 1.27 1.27)
					(thickness 0.15)
				)
			)
		)
		(property "Author" "Antmicro"
			(at 157.48 66.04 0)
			(effects
				(font
					(size 1.27 1.27)
					(thickness 0.15)
				)
				(justify left bottom)
				(hide yes)
			)
		)
		(property "License" "Apache-2.0"
			(at 157.48 68.58 0)
			(effects
				(font
					(size 1.27 1.27)
					(thickness 0.15)
				)
				(justify left bottom)
				(hide yes)
			)
		)
		(pin "A1"
		)
		(pin "A2"
		)
		(pin "A3"
		)
		(pin "A7"
		)
		(pin "A8"
		)
		(pin "A9"
		)
		(pin "B1"
		)
		(pin "B2"
		)
		(pin "B3"
		)
		(pin "B7"
		)
		(pin "B8"
		)
		(pin "B9"
		)
		(pin "C1"
		)
		(pin "C2"
		)
		(pin "C3"
		)
		(pin "C7"
		)
		(pin "C8"
		)
		(pin "C9"
		)
		(pin "D1"
		)
		(pin "D2"
		)
		(pin "D3"
		)
		(pin "D7"
		)
		(pin "D8"
		)
		(pin "D9"
		)
		(pin "E1"
		)
		(pin "E2"
		)
		(pin "E3"
		)
		(pin "E7"
		)
		(pin "E8"
		)
		(pin "E9"
		)
		(pin "F1"
		)
		(pin "F2"
		)
		(pin "F3"
		)
		(pin "F7"
		)
		(pin "F8"
		)
		(pin "F9"
		)
		(pin "G1"
		)
		(pin "G2"
		)
		(pin "G3"
		)
		(pin "G7"
		)
		(pin "G8"
		)
		(pin "G9"
		)
		(pin "H1"
		)
		(pin "H2"
		)
		(pin "H3"
		)
		(pin "H7"
		)
		(pin "H8"
		)
		(pin "H9"
		)
		(pin "J1"
		)
		(pin "J2"
		)
		(pin "J3"
		)
		(pin "J7"
		)
		(pin "J8"
		)
		(pin "J9"
		)
		(pin "K1"
		)
		(pin "K2"
		)
		(pin "K3"
		)
		(pin "K7"
		)
		(pin "K8"
		)
		(pin "K9"
		)
		(pin "L1"
		)
		(pin "L2"
		)
		(pin "L3"
		)
		(pin "L7"
		)
		(pin "L8"
		)
		(pin "L9"
		)
		(pin "M1"
		)
		(pin "M2"
		)
		(pin "M3"
		)
		(pin "M7"
		)
		(pin "M8"
		)
		(pin "M9"
		)
		(pin "N1"
		)
		(pin "N2"
		)
		(pin "N3"
		)
		(pin "N7"
		)
		(pin "N8"
		)
		(pin "N9"
		)
		(instances
			(project "k410t-devboard"
				(path ""
					(reference "U5")
					(unit 1)
				)
			)
		)
	)
	(symbol
		(lib_id "antmicroCapacitors0402:C_100n_0402")
		(at 351.79 50.8 90)
		(unit 1)
		(exclude_from_sim no)
		(in_bom yes)
		(on_board yes)
		(dnp no)
		(property "Reference" "C174"
			(at 352.425 46.355 90)
			(effects
				(font
					(size 1.27 1.27)
				)
				(justify right)
			)
		)
		(property "Value" "C_100n_0402"
			(at 361.95 30.48 0)
			(effects
				(font
					(size 1.27 1.27)
					(thickness 0.15)
				)
				(justify left bottom)
				(hide yes)
			)
		)
		(property "Footprint" "antmicro-footprints:C_0402_1005Metric"
			(at 364.49 30.48 0)
			(effects
				(font
					(size 1.27 1.27)
					(thickness 0.15)
				)
				(justify left bottom)
				(hide yes)
			)
		)
		(property "Datasheet" "https://www.murata.com/products/productdetail?partno=GRM155R61H104KE14%23"
			(at 367.03 30.48 0)
			(effects
				(font
					(size 1.27 1.27)
					(thickness 0.15)
				)
				(justify left bottom)
				(hide yes)
			)
		)
		(property "Description" ""
			(at 351.79 50.8 0)
			(effects
				(font
					(size 1.27 1.27)
				)
			)
		)
		(property "Manufacturer" "Murata"
			(at 372.11 30.48 0)
			(effects
				(font
					(size 1.27 1.27)
					(thickness 0.15)
				)
				(justify left bottom)
				(hide yes)
			)
		)
		(property "MPN" "GRM155R61H104KE14D"
			(at 369.57 30.48 0)
			(effects
				(font
					(size 1.27 1.27)
					(thickness 0.15)
				)
				(justify left bottom)
				(hide yes)
			)
		)
		(property "Val" "100n"
			(at 352.425 50.165 90)
			(effects
				(font
					(size 1.27 1.27)
					(thickness 0.15)
				)
				(justify right)
			)
		)
		(property "License" "Apache-2.0"
			(at 374.65 30.48 0)
			(effects
				(font
					(size 1.27 1.27)
					(thickness 0.15)
				)
				(justify left bottom)
				(hide yes)
			)
		)
		(property "Author" "Antmicro"
			(at 377.19 30.48 0)
			(effects
				(font
					(size 1.27 1.27)
					(thickness 0.15)
				)
				(justify left bottom)
				(hide yes)
			)
		)
		(property "Voltage" "50V"
			(at 379.73 30.48 0)
			(effects
				(font
					(size 1.27 1.27)
				)
				(justify left bottom)
				(hide yes)
			)
		)
		(property "Dielectric" "X5R"
			(at 382.27 30.48 0)
			(effects
				(font
					(size 1.27 1.27)
				)
				(justify left bottom)
				(hide yes)
			)
		)
		(pin "1"
		)
		(pin "2"
		)
		(instances
			(project "k410t-devboard"
				(path ""
					(reference "C174")
					(unit 1)
				)
			)
		)
	)
	(symbol
		(lib_id "antmicroMemory:AS6C8008-55BIN")
		(at 111.76 199.39 0)
		(unit 1)
		(exclude_from_sim no)
		(in_bom yes)
		(on_board yes)
		(dnp no)
		(fields_autoplaced yes)
		(property "Reference" "U4"
			(at 124.46 191.77 0)
			(effects
				(font
					(size 1.27 1.27)
				)
			)
		)
		(property "Value" "AS6C8008-55BIN"
			(at 124.46 194.31 0)
			(effects
				(font
					(size 1.27 1.27)
				)
				(hide yes)
			)
		)
		(property "Footprint" "antmicro-footprints:Alliance_TFBGA-48"
			(at 152.4 207.01 0)
			(effects
				(font
					(size 1.27 1.27)
					(thickness 0.15)
				)
				(justify left bottom)
				(hide yes)
			)
		)
		(property "Datasheet" "https://www.alliancememory.com/wp-content/uploads/pdf/lp_sram/AllianceMemory_8M_LPSRAM_AS6C8008_v1.1_May%202021.pdf"
			(at 152.4 209.55 0)
			(effects
				(font
					(size 1.27 1.27)
					(thickness 0.15)
				)
				(justify left bottom)
				(hide yes)
			)
		)
		(property "Description" ""
			(at 111.76 199.39 0)
			(effects
				(font
					(size 1.27 1.27)
				)
			)
		)
		(property "MPN" "AS6C8008-55BIN"
			(at 124.46 194.31 0)
			(effects
				(font
					(size 1.27 1.27)
					(thickness 0.15)
				)
			)
		)
		(property "Manufacturer" "Alliance Memory"
			(at 152.4 214.63 0)
			(effects
				(font
					(size 1.27 1.27)
					(thickness 0.15)
				)
				(justify left bottom)
				(hide yes)
			)
		)
		(property "Author" "Antmicro"
			(at 152.4 217.17 0)
			(effects
				(font
					(size 1.27 1.27)
					(thickness 0.15)
				)
				(justify left bottom)
				(hide yes)
			)
		)
		(property "License" "Apache-2.0"
			(at 152.4 219.71 0)
			(effects
				(font
					(size 1.27 1.27)
					(thickness 0.15)
				)
				(justify left bottom)
				(hide yes)
			)
		)
		(pin "A1"
		)
		(pin "A2"
		)
		(pin "A3"
		)
		(pin "A4"
		)
		(pin "A5"
		)
		(pin "A6"
		)
		(pin "B1"
		)
		(pin "B2"
		)
		(pin "B3"
		)
		(pin "B4"
		)
		(pin "B5"
		)
		(pin "B6"
		)
		(pin "C1"
		)
		(pin "C2"
		)
		(pin "C3"
		)
		(pin "C4"
		)
		(pin "C5"
		)
		(pin "C6"
		)
		(pin "D1"
		)
		(pin "D2"
		)
		(pin "D3"
		)
		(pin "D4"
		)
		(pin "D5"
		)
		(pin "D6"
		)
		(pin "E1"
		)
		(pin "E2"
		)
		(pin "E3"
		)
		(pin "E4"
		)
		(pin "E5"
		)
		(pin "E6"
		)
		(pin "F1"
		)
		(pin "F2"
		)
		(pin "F3"
		)
		(pin "F4"
		)
		(pin "F5"
		)
		(pin "F6"
		)
		(pin "G1"
		)
		(pin "G2"
		)
		(pin "G3"
		)
		(pin "G4"
		)
		(pin "G5"
		)
		(pin "G6"
		)
		(pin "H1"
		)
		(pin "H2"
		)
		(pin "H3"
		)
		(pin "H4"
		)
		(pin "H5"
		)
		(pin "H6"
		)
		(instances
			(project "k410t-devboard"
				(path ""
					(reference "U4")
					(unit 1)
				)
			)
		)
	)
	(symbol
		(lib_id "antmicropower:GND")
		(at 311.15 62.23 0)
		(unit 1)
		(exclude_from_sim no)
		(in_bom yes)
		(on_board yes)
		(dnp no)
		(property "Reference" "#PWR087"
			(at 311.15 68.58 0)
			(effects
				(font
					(size 1.27 1.27)
				)
				(hide yes)
			)
		)
		(property "Value" "GND"
			(at 311.15 66.04 0)
			(effects
				(font
					(size 1.27 1.27)
				)
			)
		)
		(property "Footprint" ""
			(at 320.04 69.85 0)
			(effects
				(font
					(size 1.27 1.27)
					(thickness 0.15)
				)
				(justify left bottom)
				(hide yes)
			)
		)
		(property "Datasheet" ""
			(at 320.04 74.93 0)
			(effects
				(font
					(size 1.27 1.27)
					(thickness 0.15)
				)
				(justify left bottom)
				(hide yes)
			)
		)
		(property "Description" ""
			(at 311.15 62.23 0)
			(effects
				(font
					(size 1.27 1.27)
				)
			)
		)
		(property "Author" "Antmicro"
			(at 320.04 69.85 0)
			(effects
				(font
					(size 1.27 1.27)
					(thickness 0.15)
				)
				(justify left bottom)
				(hide yes)
			)
		)
		(property "License" "Apache-2.0"
			(at 320.04 72.39 0)
			(effects
				(font
					(size 1.27 1.27)
					(thickness 0.15)
				)
				(justify left bottom)
				(hide yes)
			)
		)
		(pin "1"
		)
		(instances
			(project "k410t-devboard"
				(path ""
					(reference "#PWR087")
					(unit 1)
				)
			)
		)
	)
	(symbol
		(lib_id "antmicropower:GND")
		(at 187.96 63.5 0)
		(unit 1)
		(exclude_from_sim no)
		(in_bom yes)
		(on_board yes)
		(dnp no)
		(property "Reference" "#PWR071"
			(at 187.96 69.85 0)
			(effects
				(font
					(size 1.27 1.27)
				)
				(hide yes)
			)
		)
		(property "Value" "GND"
			(at 187.96 67.31 0)
			(effects
				(font
					(size 1.27 1.27)
				)
			)
		)
		(property "Footprint" ""
			(at 196.85 71.12 0)
			(effects
				(font
					(size 1.27 1.27)
					(thickness 0.15)
				)
				(justify left bottom)
				(hide yes)
			)
		)
		(property "Datasheet" ""
			(at 196.85 76.2 0)
			(effects
				(font
					(size 1.27 1.27)
					(thickness 0.15)
				)
				(justify left bottom)
				(hide yes)
			)
		)
		(property "Description" ""
			(at 187.96 63.5 0)
			(effects
				(font
					(size 1.27 1.27)
				)
			)
		)
		(property "Author" "Antmicro"
			(at 196.85 71.12 0)
			(effects
				(font
					(size 1.27 1.27)
					(thickness 0.15)
				)
				(justify left bottom)
				(hide yes)
			)
		)
		(property "License" "Apache-2.0"
			(at 196.85 73.66 0)
			(effects
				(font
					(size 1.27 1.27)
					(thickness 0.15)
				)
				(justify left bottom)
				(hide yes)
			)
		)
		(pin "1"
		)
		(instances
			(project "k410t-devboard"
				(path ""
					(reference "#PWR071")
					(unit 1)
				)
			)
		)
	)
	(symbol
		(lib_id "antmicropower:+0V675_VTT")
		(at 300.99 50.8 0)
		(mirror y)
		(unit 1)
		(exclude_from_sim no)
		(in_bom yes)
		(on_board yes)
		(dnp no)
		(fields_autoplaced yes)
		(property "Reference" "#PWR061"
			(at 300.99 54.61 0)
			(effects
				(font
					(size 1.27 1.27)
				)
				(hide yes)
			)
		)
		(property "Value" "+0V675_VTT"
			(at 300.99 47.244 0)
			(effects
				(font
					(size 1.27 1.27)
				)
			)
		)
		(property "Footprint" ""
			(at 300.99 50.8 0)
			(effects
				(font
					(size 1.27 1.27)
				)
				(hide yes)
			)
		)
		(property "Datasheet" ""
			(at 300.99 50.8 0)
			(effects
				(font
					(size 1.27 1.27)
				)
				(hide yes)
			)
		)
		(property "Description" ""
			(at 300.99 50.8 0)
			(effects
				(font
					(size 1.27 1.27)
				)
			)
		)
		(pin "1"
		)
		(instances
			(project "k410t-devboard"
				(path ""
					(reference "#PWR061")
					(unit 1)
				)
			)
		)
	)
	(symbol
		(lib_id "antmicroResistors0402:R_240R_0402")
		(at 156.21 113.03 90)
		(unit 1)
		(exclude_from_sim no)
		(in_bom yes)
		(on_board yes)
		(dnp no)
		(property "Reference" "R35"
			(at 157.48 109.22 90)
			(effects
				(font
					(size 1.27 1.27)
				)
				(justify right)
			)
		)
		(property "Value" "R_240R_0402"
			(at 168.91 92.71 0)
			(effects
				(font
					(size 1.27 1.27)
					(thickness 0.15)
				)
				(justify left bottom)
				(hide yes)
			)
		)
		(property "Footprint" "antmicro-footprints:R_0402_1005Metric"
			(at 171.45 92.71 0)
			(effects
				(font
					(size 1.27 1.27)
					(thickness 0.15)
				)
				(justify left bottom)
				(hide yes)
			)
		)
		(property "Datasheet" "https://www.bourns.com/docs/product-datasheets/cr.pdf"
			(at 173.99 92.71 0)
			(effects
				(font
					(size 1.27 1.27)
					(thickness 0.15)
				)
				(justify left bottom)
				(hide yes)
			)
		)
		(property "Description" ""
			(at 156.21 113.03 0)
			(effects
				(font
					(size 1.27 1.27)
				)
			)
		)
		(property "Manufacturer" "Bourns"
			(at 179.07 92.71 0)
			(effects
				(font
					(size 1.27 1.27)
					(thickness 0.15)
				)
				(justify left bottom)
				(hide yes)
			)
		)
		(property "MPN" "CR0402-FX-2400GLF"
			(at 176.53 92.71 0)
			(effects
				(font
					(size 1.27 1.27)
					(thickness 0.15)
				)
				(justify left bottom)
				(hide yes)
			)
		)
		(property "Val" "240R"
			(at 157.48 111.76 90)
			(effects
				(font
					(size 1.27 1.27)
					(thickness 0.15)
				)
				(justify right)
			)
		)
		(property "License" "Apache-2.0"
			(at 181.61 92.71 0)
			(effects
				(font
					(size 1.27 1.27)
					(thickness 0.15)
				)
				(justify left bottom)
				(hide yes)
			)
		)
		(property "Author" "Antmicro"
			(at 184.15 92.71 0)
			(effects
				(font
					(size 1.27 1.27)
					(thickness 0.15)
				)
				(justify left bottom)
				(hide yes)
			)
		)
		(property "Tolerance" "1%"
			(at 166.37 92.71 0)
			(effects
				(font
					(size 1.27 1.27)
				)
				(justify left bottom)
				(hide yes)
			)
		)
		(pin "1"
		)
		(pin "2"
		)
		(instances
			(project "k410t-devboard"
				(path ""
					(reference "R35")
					(unit 1)
				)
			)
		)
	)
	(symbol
		(lib_id "antmicropower:GND")
		(at 257.81 35.56 0)
		(unit 1)
		(exclude_from_sim no)
		(in_bom yes)
		(on_board yes)
		(dnp no)
		(property "Reference" "#PWR083"
			(at 257.81 41.91 0)
			(effects
				(font
					(size 1.27 1.27)
				)
				(hide yes)
			)
		)
		(property "Value" "GND"
			(at 257.81 39.37 0)
			(effects
				(font
					(size 1.27 1.27)
				)
			)
		)
		(property "Footprint" ""
			(at 266.7 43.18 0)
			(effects
				(font
					(size 1.27 1.27)
					(thickness 0.15)
				)
				(justify left bottom)
				(hide yes)
			)
		)
		(property "Datasheet" ""
			(at 266.7 48.26 0)
			(effects
				(font
					(size 1.27 1.27)
					(thickness 0.15)
				)
				(justify left bottom)
				(hide yes)
			)
		)
		(property "Description" ""
			(at 257.81 35.56 0)
			(effects
				(font
					(size 1.27 1.27)
				)
			)
		)
		(property "Author" "Antmicro"
			(at 266.7 43.18 0)
			(effects
				(font
					(size 1.27 1.27)
					(thickness 0.15)
				)
				(justify left bottom)
				(hide yes)
			)
		)
		(property "License" "Apache-2.0"
			(at 266.7 45.72 0)
			(effects
				(font
					(size 1.27 1.27)
					(thickness 0.15)
				)
				(justify left bottom)
				(hide yes)
			)
		)
		(pin "1"
		)
		(instances
			(project "k410t-devboard"
				(path ""
					(reference "#PWR083")
					(unit 1)
				)
			)
		)
	)
	(symbol
		(lib_id "antmicropower:GND")
		(at 250.19 35.56 0)
		(unit 1)
		(exclude_from_sim no)
		(in_bom yes)
		(on_board yes)
		(dnp no)
		(property "Reference" "#PWR081"
			(at 250.19 41.91 0)
			(effects
				(font
					(size 1.27 1.27)
				)
				(hide yes)
			)
		)
		(property "Value" "GND"
			(at 250.19 39.37 0)
			(effects
				(font
					(size 1.27 1.27)
				)
			)
		)
		(property "Footprint" ""
			(at 259.08 43.18 0)
			(effects
				(font
					(size 1.27 1.27)
					(thickness 0.15)
				)
				(justify left bottom)
				(hide yes)
			)
		)
		(property "Datasheet" ""
			(at 259.08 48.26 0)
			(effects
				(font
					(size 1.27 1.27)
					(thickness 0.15)
				)
				(justify left bottom)
				(hide yes)
			)
		)
		(property "Description" ""
			(at 250.19 35.56 0)
			(effects
				(font
					(size 1.27 1.27)
				)
			)
		)
		(property "Author" "Antmicro"
			(at 259.08 43.18 0)
			(effects
				(font
					(size 1.27 1.27)
					(thickness 0.15)
				)
				(justify left bottom)
				(hide yes)
			)
		)
		(property "License" "Apache-2.0"
			(at 259.08 45.72 0)
			(effects
				(font
					(size 1.27 1.27)
					(thickness 0.15)
				)
				(justify left bottom)
				(hide yes)
			)
		)
		(pin "1"
		)
		(instances
			(project "k410t-devboard"
				(path ""
					(reference "#PWR081")
					(unit 1)
				)
			)
		)
	)
	(symbol
		(lib_id "antmicropower:GND")
		(at 266.7 35.56 0)
		(unit 1)
		(exclude_from_sim no)
		(in_bom yes)
		(on_board yes)
		(dnp no)
		(property "Reference" "#PWR084"
			(at 266.7 41.91 0)
			(effects
				(font
					(size 1.27 1.27)
				)
				(hide yes)
			)
		)
		(property "Value" "GND"
			(at 266.7 39.37 0)
			(effects
				(font
					(size 1.27 1.27)
				)
			)
		)
		(property "Footprint" ""
			(at 275.59 43.18 0)
			(effects
				(font
					(size 1.27 1.27)
					(thickness 0.15)
				)
				(justify left bottom)
				(hide yes)
			)
		)
		(property "Datasheet" ""
			(at 275.59 48.26 0)
			(effects
				(font
					(size 1.27 1.27)
					(thickness 0.15)
				)
				(justify left bottom)
				(hide yes)
			)
		)
		(property "Description" ""
			(at 266.7 35.56 0)
			(effects
				(font
					(size 1.27 1.27)
				)
			)
		)
		(property "Author" "Antmicro"
			(at 275.59 43.18 0)
			(effects
				(font
					(size 1.27 1.27)
					(thickness 0.15)
				)
				(justify left bottom)
				(hide yes)
			)
		)
		(property "License" "Apache-2.0"
			(at 275.59 45.72 0)
			(effects
				(font
					(size 1.27 1.27)
					(thickness 0.15)
				)
				(justify left bottom)
				(hide yes)
			)
		)
		(pin "1"
		)
		(instances
			(project "k410t-devboard"
				(path ""
					(reference "#PWR084")
					(unit 1)
				)
			)
		)
	)
	(symbol
		(lib_id "antmicroResistorNetworksArrays:4x39R_0201_array")
		(at 257.81 87.63 0)
		(unit 1)
		(exclude_from_sim no)
		(in_bom yes)
		(on_board yes)
		(dnp no)
		(fields_autoplaced yes)
		(property "Reference" "R12"
			(at 262.89 80.645 0)
			(effects
				(font
					(size 1.27 1.27)
				)
			)
		)
		(property "Value" "4x39R_0201_array"
			(at 284.48 93.345 0)
			(effects
				(font
					(size 1.27 1.27)
					(thickness 0.15)
				)
				(justify left bottom)
				(hide yes)
			)
		)
		(property "Footprint" "antmicro-footprints:R_Array_4x0201_Panasonic_EXB18V"
			(at 284.48 98.425 0)
			(effects
				(font
					(size 1.27 1.27)
					(thickness 0.15)
				)
				(justify left bottom)
				(hide yes)
			)
		)
		(property "Datasheet" "https://eu.mouser.com/datasheet/2/315/AOC0000C14-1108062.pdf"
			(at 284.48 100.965 0)
			(effects
				(font
					(size 1.27 1.27)
					(thickness 0.15)
				)
				(justify left bottom)
				(hide yes)
			)
		)
		(property "Description" ""
			(at 257.81 87.63 0)
			(effects
				(font
					(size 1.27 1.27)
				)
			)
		)
		(property "MPN" "EXB-18V390JX"
			(at 284.48 103.505 0)
			(effects
				(font
					(size 1.27 1.27)
					(thickness 0.15)
				)
				(justify left bottom)
				(hide yes)
			)
		)
		(property "Manufacturer" "Panasonic"
			(at 284.48 106.045 0)
			(effects
				(font
					(size 1.27 1.27)
					(thickness 0.15)
				)
				(justify left bottom)
				(hide yes)
			)
		)
		(property "Author" "Antmicro"
			(at 284.48 108.585 0)
			(effects
				(font
					(size 1.27 1.27)
					(thickness 0.15)
				)
				(justify left bottom)
				(hide yes)
			)
		)
		(property "License" "Apache-2.0"
			(at 284.48 111.125 0)
			(effects
				(font
					(size 1.27 1.27)
					(thickness 0.15)
				)
				(justify left bottom)
				(hide yes)
			)
		)
		(property "Val" "4x39R_0201"
			(at 262.89 83.185 0)
			(effects
				(font
					(size 1.27 1.27)
				)
			)
		)
		(pin "1"
		)
		(pin "2"
		)
		(pin "3"
		)
		(pin "4"
		)
		(pin "5"
		)
		(pin "6"
		)
		(pin "7"
		)
		(pin "8"
		)
		(instances
			(project "k410t-devboard"
				(path ""
					(reference "R12")
					(unit 1)
				)
			)
		)
	)
	(symbol
		(lib_id "antmicroResistorNetworksArrays:4x39R_0201_array")
		(at 257.81 104.14 0)
		(unit 1)
		(exclude_from_sim no)
		(in_bom yes)
		(on_board yes)
		(dnp no)
		(fields_autoplaced yes)
		(property "Reference" "R13"
			(at 262.89 115.57 0)
			(effects
				(font
					(size 1.27 1.27)
				)
			)
		)
		(property "Value" "4x39R_0201_array"
			(at 284.48 109.855 0)
			(effects
				(font
					(size 1.27 1.27)
					(thickness 0.15)
				)
				(justify left bottom)
				(hide yes)
			)
		)
		(property "Footprint" "antmicro-footprints:R_Array_4x0201_Panasonic_EXB18V"
			(at 284.48 114.935 0)
			(effects
				(font
					(size 1.27 1.27)
					(thickness 0.15)
				)
				(justify left bottom)
				(hide yes)
			)
		)
		(property "Datasheet" "https://eu.mouser.com/datasheet/2/315/AOC0000C14-1108062.pdf"
			(at 284.48 117.475 0)
			(effects
				(font
					(size 1.27 1.27)
					(thickness 0.15)
				)
				(justify left bottom)
				(hide yes)
			)
		)
		(property "Description" ""
			(at 257.81 104.14 0)
			(effects
				(font
					(size 1.27 1.27)
				)
			)
		)
		(property "MPN" "EXB-18V390JX"
			(at 284.48 120.015 0)
			(effects
				(font
					(size 1.27 1.27)
					(thickness 0.15)
				)
				(justify left bottom)
				(hide yes)
			)
		)
		(property "Manufacturer" "Panasonic"
			(at 284.48 122.555 0)
			(effects
				(font
					(size 1.27 1.27)
					(thickness 0.15)
				)
				(justify left bottom)
				(hide yes)
			)
		)
		(property "Author" "Antmicro"
			(at 284.48 125.095 0)
			(effects
				(font
					(size 1.27 1.27)
					(thickness 0.15)
				)
				(justify left bottom)
				(hide yes)
			)
		)
		(property "License" "Apache-2.0"
			(at 284.48 127.635 0)
			(effects
				(font
					(size 1.27 1.27)
					(thickness 0.15)
				)
				(justify left bottom)
				(hide yes)
			)
		)
		(property "Val" "4x39R_0201"
			(at 262.89 118.11 0)
			(effects
				(font
					(size 1.27 1.27)
				)
			)
		)
		(pin "1"
		)
		(pin "2"
		)
		(pin "3"
		)
		(pin "4"
		)
		(pin "5"
		)
		(pin "6"
		)
		(pin "7"
		)
		(pin "8"
		)
		(instances
			(project "k410t-devboard"
				(path ""
					(reference "R13")
					(unit 1)
				)
			)
		)
	)
	(symbol
		(lib_id "antmicroCapacitors0402:C_100n_0402")
		(at 196.85 33.02 90)
		(unit 1)
		(exclude_from_sim no)
		(in_bom yes)
		(on_board yes)
		(dnp no)
		(property "Reference" "C185"
			(at 197.485 28.575 90)
			(effects
				(font
					(size 1.27 1.27)
				)
				(justify right)
			)
		)
		(property "Value" "C_100n_0402"
			(at 207.01 12.7 0)
			(effects
				(font
					(size 1.27 1.27)
					(thickness 0.15)
				)
				(justify left bottom)
				(hide yes)
			)
		)
		(property "Footprint" "antmicro-footprints:C_0402_1005Metric"
			(at 209.55 12.7 0)
			(effects
				(font
					(size 1.27 1.27)
					(thickness 0.15)
				)
				(justify left bottom)
				(hide yes)
			)
		)
		(property "Datasheet" "https://www.murata.com/products/productdetail?partno=GRM155R61H104KE14%23"
			(at 212.09 12.7 0)
			(effects
				(font
					(size 1.27 1.27)
					(thickness 0.15)
				)
				(justify left bottom)
				(hide yes)
			)
		)
		(property "Description" ""
			(at 196.85 33.02 0)
			(effects
				(font
					(size 1.27 1.27)
				)
			)
		)
		(property "Manufacturer" "Murata"
			(at 217.17 12.7 0)
			(effects
				(font
					(size 1.27 1.27)
					(thickness 0.15)
				)
				(justify left bottom)
				(hide yes)
			)
		)
		(property "MPN" "GRM155R61H104KE14D"
			(at 214.63 12.7 0)
			(effects
				(font
					(size 1.27 1.27)
					(thickness 0.15)
				)
				(justify left bottom)
				(hide yes)
			)
		)
		(property "Val" "100n"
			(at 197.485 32.385 90)
			(effects
				(font
					(size 1.27 1.27)
					(thickness 0.15)
				)
				(justify right)
			)
		)
		(property "License" "Apache-2.0"
			(at 219.71 12.7 0)
			(effects
				(font
					(size 1.27 1.27)
					(thickness 0.15)
				)
				(justify left bottom)
				(hide yes)
			)
		)
		(property "Author" "Antmicro"
			(at 222.25 12.7 0)
			(effects
				(font
					(size 1.27 1.27)
					(thickness 0.15)
				)
				(justify left bottom)
				(hide yes)
			)
		)
		(property "Voltage" "50V"
			(at 224.79 12.7 0)
			(effects
				(font
					(size 1.27 1.27)
				)
				(justify left bottom)
				(hide yes)
			)
		)
		(property "Dielectric" "X5R"
			(at 227.33 12.7 0)
			(effects
				(font
					(size 1.27 1.27)
				)
				(justify left bottom)
				(hide yes)
			)
		)
		(pin "1"
		)
		(pin "2"
		)
		(instances
			(project "k410t-devboard"
				(path ""
					(reference "C185")
					(unit 1)
				)
			)
		)
	)
	(symbol
		(lib_id "antmicroCapacitors0402:C_100n_0402")
		(at 351.79 59.69 90)
		(unit 1)
		(exclude_from_sim no)
		(in_bom yes)
		(on_board yes)
		(dnp no)
		(property "Reference" "C175"
			(at 352.425 55.245 90)
			(effects
				(font
					(size 1.27 1.27)
				)
				(justify right)
			)
		)
		(property "Value" "C_100n_0402"
			(at 361.95 39.37 0)
			(effects
				(font
					(size 1.27 1.27)
					(thickness 0.15)
				)
				(justify left bottom)
				(hide yes)
			)
		)
		(property "Footprint" "antmicro-footprints:C_0402_1005Metric"
			(at 364.49 39.37 0)
			(effects
				(font
					(size 1.27 1.27)
					(thickness 0.15)
				)
				(justify left bottom)
				(hide yes)
			)
		)
		(property "Datasheet" "https://www.murata.com/products/productdetail?partno=GRM155R61H104KE14%23"
			(at 367.03 39.37 0)
			(effects
				(font
					(size 1.27 1.27)
					(thickness 0.15)
				)
				(justify left bottom)
				(hide yes)
			)
		)
		(property "Description" ""
			(at 351.79 59.69 0)
			(effects
				(font
					(size 1.27 1.27)
				)
			)
		)
		(property "Manufacturer" "Murata"
			(at 372.11 39.37 0)
			(effects
				(font
					(size 1.27 1.27)
					(thickness 0.15)
				)
				(justify left bottom)
				(hide yes)
			)
		)
		(property "MPN" "GRM155R61H104KE14D"
			(at 369.57 39.37 0)
			(effects
				(font
					(size 1.27 1.27)
					(thickness 0.15)
				)
				(justify left bottom)
				(hide yes)
			)
		)
		(property "Val" "100n"
			(at 352.425 59.055 90)
			(effects
				(font
					(size 1.27 1.27)
					(thickness 0.15)
				)
				(justify right)
			)
		)
		(property "License" "Apache-2.0"
			(at 374.65 39.37 0)
			(effects
				(font
					(size 1.27 1.27)
					(thickness 0.15)
				)
				(justify left bottom)
				(hide yes)
			)
		)
		(property "Author" "Antmicro"
			(at 377.19 39.37 0)
			(effects
				(font
					(size 1.27 1.27)
					(thickness 0.15)
				)
				(justify left bottom)
				(hide yes)
			)
		)
		(property "Voltage" "50V"
			(at 379.73 39.37 0)
			(effects
				(font
					(size 1.27 1.27)
				)
				(justify left bottom)
				(hide yes)
			)
		)
		(property "Dielectric" "X5R"
			(at 382.27 39.37 0)
			(effects
				(font
					(size 1.27 1.27)
				)
				(justify left bottom)
				(hide yes)
			)
		)
		(pin "1"
		)
		(pin "2"
		)
		(instances
			(project "k410t-devboard"
				(path ""
					(reference "C175")
					(unit 1)
				)
			)
		)
	)
	(symbol
		(lib_id "antmicropower:GND")
		(at 156.21 114.3 0)
		(unit 1)
		(exclude_from_sim no)
		(in_bom yes)
		(on_board yes)
		(dnp no)
		(property "Reference" "#PWR065"
			(at 156.21 120.65 0)
			(effects
				(font
					(size 1.27 1.27)
				)
				(hide yes)
			)
		)
		(property "Value" "GND"
			(at 156.21 118.11 0)
			(effects
				(font
					(size 1.27 1.27)
				)
			)
		)
		(property "Footprint" ""
			(at 165.1 121.92 0)
			(effects
				(font
					(size 1.27 1.27)
					(thickness 0.15)
				)
				(justify left bottom)
				(hide yes)
			)
		)
		(property "Datasheet" ""
			(at 165.1 127 0)
			(effects
				(font
					(size 1.27 1.27)
					(thickness 0.15)
				)
				(justify left bottom)
				(hide yes)
			)
		)
		(property "Description" ""
			(at 156.21 114.3 0)
			(effects
				(font
					(size 1.27 1.27)
				)
			)
		)
		(property "Author" "Antmicro"
			(at 165.1 121.92 0)
			(effects
				(font
					(size 1.27 1.27)
					(thickness 0.15)
				)
				(justify left bottom)
				(hide yes)
			)
		)
		(property "License" "Apache-2.0"
			(at 165.1 124.46 0)
			(effects
				(font
					(size 1.27 1.27)
					(thickness 0.15)
				)
				(justify left bottom)
				(hide yes)
			)
		)
		(pin "1"
		)
		(instances
			(project "k410t-devboard"
				(path ""
					(reference "#PWR065")
					(unit 1)
				)
			)
		)
	)
	(symbol
		(lib_id "antmicropower:GND")
		(at 223.52 35.56 0)
		(unit 1)
		(exclude_from_sim no)
		(in_bom yes)
		(on_board yes)
		(dnp no)
		(property "Reference" "#PWR078"
			(at 223.52 41.91 0)
			(effects
				(font
					(size 1.27 1.27)
				)
				(hide yes)
			)
		)
		(property "Value" "GND"
			(at 223.52 39.37 0)
			(effects
				(font
					(size 1.27 1.27)
				)
			)
		)
		(property "Footprint" ""
			(at 232.41 43.18 0)
			(effects
				(font
					(size 1.27 1.27)
					(thickness 0.15)
				)
				(justify left bottom)
				(hide yes)
			)
		)
		(property "Datasheet" ""
			(at 232.41 48.26 0)
			(effects
				(font
					(size 1.27 1.27)
					(thickness 0.15)
				)
				(justify left bottom)
				(hide yes)
			)
		)
		(property "Description" ""
			(at 223.52 35.56 0)
			(effects
				(font
					(size 1.27 1.27)
				)
			)
		)
		(property "Author" "Antmicro"
			(at 232.41 43.18 0)
			(effects
				(font
					(size 1.27 1.27)
					(thickness 0.15)
				)
				(justify left bottom)
				(hide yes)
			)
		)
		(property "License" "Apache-2.0"
			(at 232.41 45.72 0)
			(effects
				(font
					(size 1.27 1.27)
					(thickness 0.15)
				)
				(justify left bottom)
				(hide yes)
			)
		)
		(pin "1"
		)
		(instances
			(project "k410t-devboard"
				(path ""
					(reference "#PWR078")
					(unit 1)
				)
			)
		)
	)
	(symbol
		(lib_id "antmicroResistorNetworksArrays:4x39R_0201_array")
		(at 359.41 87.63 0)
		(unit 1)
		(exclude_from_sim no)
		(in_bom yes)
		(on_board yes)
		(dnp no)
		(fields_autoplaced yes)
		(property "Reference" "R16"
			(at 364.49 80.645 0)
			(effects
				(font
					(size 1.27 1.27)
				)
			)
		)
		(property "Value" "4x39R_0201_array"
			(at 386.08 93.345 0)
			(effects
				(font
					(size 1.27 1.27)
					(thickness 0.15)
				)
				(justify left bottom)
				(hide yes)
			)
		)
		(property "Footprint" "antmicro-footprints:R_Array_4x0201_Panasonic_EXB18V"
			(at 386.08 98.425 0)
			(effects
				(font
					(size 1.27 1.27)
					(thickness 0.15)
				)
				(justify left bottom)
				(hide yes)
			)
		)
		(property "Datasheet" "https://eu.mouser.com/datasheet/2/315/AOC0000C14-1108062.pdf"
			(at 386.08 100.965 0)
			(effects
				(font
					(size 1.27 1.27)
					(thickness 0.15)
				)
				(justify left bottom)
				(hide yes)
			)
		)
		(property "Description" ""
			(at 359.41 87.63 0)
			(effects
				(font
					(size 1.27 1.27)
				)
			)
		)
		(property "MPN" "EXB-18V390JX"
			(at 386.08 103.505 0)
			(effects
				(font
					(size 1.27 1.27)
					(thickness 0.15)
				)
				(justify left bottom)
				(hide yes)
			)
		)
		(property "Manufacturer" "Panasonic"
			(at 386.08 106.045 0)
			(effects
				(font
					(size 1.27 1.27)
					(thickness 0.15)
				)
				(justify left bottom)
				(hide yes)
			)
		)
		(property "Author" "Antmicro"
			(at 386.08 108.585 0)
			(effects
				(font
					(size 1.27 1.27)
					(thickness 0.15)
				)
				(justify left bottom)
				(hide yes)
			)
		)
		(property "License" "Apache-2.0"
			(at 386.08 111.125 0)
			(effects
				(font
					(size 1.27 1.27)
					(thickness 0.15)
				)
				(justify left bottom)
				(hide yes)
			)
		)
		(property "Val" "4x39R_0201"
			(at 364.49 83.185 0)
			(effects
				(font
					(size 1.27 1.27)
				)
			)
		)
		(pin "1"
		)
		(pin "2"
		)
		(pin "3"
		)
		(pin "4"
		)
		(pin "5"
		)
		(pin "6"
		)
		(pin "7"
		)
		(pin "8"
		)
		(instances
			(project "k410t-devboard"
				(path ""
					(reference "R16")
					(unit 1)
				)
			)
		)
	)
	(symbol
		(lib_id "antmicroResistors0402:R_40R2_0402")
		(at 213.36 87.63 0)
		(unit 1)
		(exclude_from_sim no)
		(in_bom yes)
		(on_board yes)
		(dnp no)
		(property "Reference" "R40"
			(at 220.345 86.36 0)
			(effects
				(font
					(size 1.27 1.27)
				)
			)
		)
		(property "Value" "R_40R2_0402"
			(at 233.68 100.33 0)
			(effects
				(font
					(size 1.27 1.27)
					(thickness 0.15)
				)
				(justify left bottom)
				(hide yes)
			)
		)
		(property "Footprint" "antmicro-footprints:R_0402_1005Metric"
			(at 233.68 102.87 0)
			(effects
				(font
					(size 1.27 1.27)
					(thickness 0.15)
				)
				(justify left bottom)
				(hide yes)
			)
		)
		(property "Datasheet" "https://www.bourns.com/docs/product-datasheets/cr.pdf"
			(at 233.68 105.41 0)
			(effects
				(font
					(size 1.27 1.27)
					(thickness 0.15)
				)
				(justify left bottom)
				(hide yes)
			)
		)
		(property "Description" ""
			(at 213.36 87.63 0)
			(effects
				(font
					(size 1.27 1.27)
				)
			)
		)
		(property "Manufacturer" "Bourns"
			(at 233.68 110.49 0)
			(effects
				(font
					(size 1.27 1.27)
					(thickness 0.15)
				)
				(justify left bottom)
				(hide yes)
			)
		)
		(property "MPN" "CR0402-FX-40R2GLF"
			(at 233.68 107.95 0)
			(effects
				(font
					(size 1.27 1.27)
					(thickness 0.15)
				)
				(justify left bottom)
				(hide yes)
			)
		)
		(property "Val" "40R2"
			(at 210.82 86.36 0)
			(effects
				(font
					(size 1.27 1.27)
					(thickness 0.15)
				)
			)
		)
		(property "License" "Apache-2.0"
			(at 233.68 113.03 0)
			(effects
				(font
					(size 1.27 1.27)
					(thickness 0.15)
				)
				(justify left bottom)
				(hide yes)
			)
		)
		(property "Author" "Antmicro"
			(at 233.68 115.57 0)
			(effects
				(font
					(size 1.27 1.27)
					(thickness 0.15)
				)
				(justify left bottom)
				(hide yes)
			)
		)
		(property "Tolerance" "1%"
			(at 233.68 97.79 0)
			(effects
				(font
					(size 1.27 1.27)
				)
				(justify left bottom)
				(hide yes)
			)
		)
		(pin "1"
		)
		(pin "2"
		)
		(instances
			(project "k410t-devboard"
				(path ""
					(reference "R40")
					(unit 1)
				)
			)
		)
	)
	(symbol
		(lib_id "antmicroCapacitors0402:C_100n_0402")
		(at 196.85 60.96 90)
		(unit 1)
		(exclude_from_sim no)
		(in_bom yes)
		(on_board yes)
		(dnp no)
		(property "Reference" "C186"
			(at 197.485 56.515 90)
			(effects
				(font
					(size 1.27 1.27)
				)
				(justify right)
			)
		)
		(property "Value" "C_100n_0402"
			(at 207.01 40.64 0)
			(effects
				(font
					(size 1.27 1.27)
					(thickness 0.15)
				)
				(justify left bottom)
				(hide yes)
			)
		)
		(property "Footprint" "antmicro-footprints:C_0402_1005Metric"
			(at 209.55 40.64 0)
			(effects
				(font
					(size 1.27 1.27)
					(thickness 0.15)
				)
				(justify left bottom)
				(hide yes)
			)
		)
		(property "Datasheet" "https://www.murata.com/products/productdetail?partno=GRM155R61H104KE14%23"
			(at 212.09 40.64 0)
			(effects
				(font
					(size 1.27 1.27)
					(thickness 0.15)
				)
				(justify left bottom)
				(hide yes)
			)
		)
		(property "Description" ""
			(at 196.85 60.96 0)
			(effects
				(font
					(size 1.27 1.27)
				)
			)
		)
		(property "Manufacturer" "Murata"
			(at 217.17 40.64 0)
			(effects
				(font
					(size 1.27 1.27)
					(thickness 0.15)
				)
				(justify left bottom)
				(hide yes)
			)
		)
		(property "MPN" "GRM155R61H104KE14D"
			(at 214.63 40.64 0)
			(effects
				(font
					(size 1.27 1.27)
					(thickness 0.15)
				)
				(justify left bottom)
				(hide yes)
			)
		)
		(property "Val" "100n"
			(at 197.485 60.325 90)
			(effects
				(font
					(size 1.27 1.27)
					(thickness 0.15)
				)
				(justify right)
			)
		)
		(property "License" "Apache-2.0"
			(at 219.71 40.64 0)
			(effects
				(font
					(size 1.27 1.27)
					(thickness 0.15)
				)
				(justify left bottom)
				(hide yes)
			)
		)
		(property "Author" "Antmicro"
			(at 222.25 40.64 0)
			(effects
				(font
					(size 1.27 1.27)
					(thickness 0.15)
				)
				(justify left bottom)
				(hide yes)
			)
		)
		(property "Voltage" "50V"
			(at 224.79 40.64 0)
			(effects
				(font
					(size 1.27 1.27)
				)
				(justify left bottom)
				(hide yes)
			)
		)
		(property "Dielectric" "X5R"
			(at 227.33 40.64 0)
			(effects
				(font
					(size 1.27 1.27)
				)
				(justify left bottom)
				(hide yes)
			)
		)
		(pin "1"
		)
		(pin "2"
		)
		(instances
			(project "k410t-devboard"
				(path ""
					(reference "C186")
					(unit 1)
				)
			)
		)
	)
	(symbol
		(lib_id "antmicropower:+0V675_VTT")
		(at 325.12 86.36 0)
		(unit 1)
		(exclude_from_sim no)
		(in_bom yes)
		(on_board yes)
		(dnp no)
		(fields_autoplaced yes)
		(property "Reference" "#PWR0276"
			(at 325.12 90.17 0)
			(effects
				(font
					(size 1.27 1.27)
				)
				(hide yes)
			)
		)
		(property "Value" "+0V675_VTT"
			(at 325.12 82.804 0)
			(effects
				(font
					(size 1.27 1.27)
				)
			)
		)
		(property "Footprint" ""
			(at 325.12 86.36 0)
			(effects
				(font
					(size 1.27 1.27)
				)
				(hide yes)
			)
		)
		(property "Datasheet" ""
			(at 325.12 86.36 0)
			(effects
				(font
					(size 1.27 1.27)
				)
				(hide yes)
			)
		)
		(property "Description" ""
			(at 325.12 86.36 0)
			(effects
				(font
					(size 1.27 1.27)
				)
			)
		)
		(pin "1"
		)
		(instances
			(project "k410t-devboard"
				(path ""
					(reference "#PWR0276")
					(unit 1)
				)
			)
		)
	)
	(symbol
		(lib_id "antmicropower:GND")
		(at 161.29 35.56 0)
		(unit 1)
		(exclude_from_sim no)
		(in_bom yes)
		(on_board yes)
		(dnp no)
		(property "Reference" "#PWR066"
			(at 161.29 41.91 0)
			(effects
				(font
					(size 1.27 1.27)
				)
				(hide yes)
			)
		)
		(property "Value" "GND"
			(at 161.29 39.37 0)
			(effects
				(font
					(size 1.27 1.27)
				)
			)
		)
		(property "Footprint" ""
			(at 170.18 43.18 0)
			(effects
				(font
					(size 1.27 1.27)
					(thickness 0.15)
				)
				(justify left bottom)
				(hide yes)
			)
		)
		(property "Datasheet" ""
			(at 170.18 48.26 0)
			(effects
				(font
					(size 1.27 1.27)
					(thickness 0.15)
				)
				(justify left bottom)
				(hide yes)
			)
		)
		(property "Description" ""
			(at 161.29 35.56 0)
			(effects
				(font
					(size 1.27 1.27)
				)
			)
		)
		(property "Author" "Antmicro"
			(at 170.18 43.18 0)
			(effects
				(font
					(size 1.27 1.27)
					(thickness 0.15)
				)
				(justify left bottom)
				(hide yes)
			)
		)
		(property "License" "Apache-2.0"
			(at 170.18 45.72 0)
			(effects
				(font
					(size 1.27 1.27)
					(thickness 0.15)
				)
				(justify left bottom)
				(hide yes)
			)
		)
		(pin "1"
		)
		(instances
			(project "k410t-devboard"
				(path ""
					(reference "#PWR066")
					(unit 1)
				)
			)
		)
	)
	(symbol
		(lib_id "antmicroCapacitors0402:C_100n_0402")
		(at 154.94 191.77 90)
		(unit 1)
		(exclude_from_sim no)
		(in_bom yes)
		(on_board yes)
		(dnp no)
		(property "Reference" "C178"
			(at 155.575 187.325 90)
			(effects
				(font
					(size 1.27 1.27)
				)
				(justify right)
			)
		)
		(property "Value" "C_100n_0402"
			(at 165.1 171.45 0)
			(effects
				(font
					(size 1.27 1.27)
					(thickness 0.15)
				)
				(justify left bottom)
				(hide yes)
			)
		)
		(property "Footprint" "antmicro-footprints:C_0402_1005Metric"
			(at 167.64 171.45 0)
			(effects
				(font
					(size 1.27 1.27)
					(thickness 0.15)
				)
				(justify left bottom)
				(hide yes)
			)
		)
		(property "Datasheet" "https://www.murata.com/products/productdetail?partno=GRM155R61H104KE14%23"
			(at 170.18 171.45 0)
			(effects
				(font
					(size 1.27 1.27)
					(thickness 0.15)
				)
				(justify left bottom)
				(hide yes)
			)
		)
		(property "Description" ""
			(at 154.94 191.77 0)
			(effects
				(font
					(size 1.27 1.27)
				)
			)
		)
		(property "Manufacturer" "Murata"
			(at 175.26 171.45 0)
			(effects
				(font
					(size 1.27 1.27)
					(thickness 0.15)
				)
				(justify left bottom)
				(hide yes)
			)
		)
		(property "MPN" "GRM155R61H104KE14D"
			(at 172.72 171.45 0)
			(effects
				(font
					(size 1.27 1.27)
					(thickness 0.15)
				)
				(justify left bottom)
				(hide yes)
			)
		)
		(property "Val" "100n"
			(at 155.575 191.135 90)
			(effects
				(font
					(size 1.27 1.27)
					(thickness 0.15)
				)
				(justify right)
			)
		)
		(property "License" "Apache-2.0"
			(at 177.8 171.45 0)
			(effects
				(font
					(size 1.27 1.27)
					(thickness 0.15)
				)
				(justify left bottom)
				(hide yes)
			)
		)
		(property "Author" "Antmicro"
			(at 180.34 171.45 0)
			(effects
				(font
					(size 1.27 1.27)
					(thickness 0.15)
				)
				(justify left bottom)
				(hide yes)
			)
		)
		(property "Voltage" "50V"
			(at 182.88 171.45 0)
			(effects
				(font
					(size 1.27 1.27)
				)
				(justify left bottom)
				(hide yes)
			)
		)
		(property "Dielectric" "X5R"
			(at 185.42 171.45 0)
			(effects
				(font
					(size 1.27 1.27)
				)
				(justify left bottom)
				(hide yes)
			)
		)
		(pin "1"
		)
		(pin "2"
		)
		(instances
			(project "k410t-devboard"
				(path ""
					(reference "C178")
					(unit 1)
				)
			)
		)
	)
	(symbol
		(lib_id "antmicroResistorNetworksArrays:4x10k_0201_array")
		(at 190.5 229.87 0)
		(unit 1)
		(exclude_from_sim no)
		(in_bom yes)
		(on_board yes)
		(dnp no)
		(fields_autoplaced yes)
		(property "Reference" "R36"
			(at 195.58 223.52 0)
			(effects
				(font
					(size 1.27 1.27)
				)
			)
		)
		(property "Value" "4x10k_0201_array"
			(at 217.17 237.49 0)
			(effects
				(font
					(size 1.27 1.27)
					(thickness 0.15)
				)
				(justify left bottom)
				(hide yes)
			)
		)
		(property "Footprint" "antmicro-footprints:R_Array_4x0201_Panasonic_EXB18V"
			(at 217.17 242.57 0)
			(effects
				(font
					(size 1.27 1.27)
					(thickness 0.15)
				)
				(justify left bottom)
				(hide yes)
			)
		)
		(property "Datasheet" "http://industrial.panasonic.com/cdbs/www-data/pdf/AOC0000/AOC0000C14.pdf"
			(at 217.17 245.11 0)
			(effects
				(font
					(size 1.27 1.27)
					(thickness 0.15)
				)
				(justify left bottom)
				(hide yes)
			)
		)
		(property "Description" ""
			(at 190.5 229.87 0)
			(effects
				(font
					(size 1.27 1.27)
				)
			)
		)
		(property "MPN" "EXB-18V103JX"
			(at 217.17 247.65 0)
			(effects
				(font
					(size 1.27 1.27)
					(thickness 0.15)
				)
				(justify left bottom)
				(hide yes)
			)
		)
		(property "Manufacturer" "Panasonic"
			(at 217.17 250.19 0)
			(effects
				(font
					(size 1.27 1.27)
					(thickness 0.15)
				)
				(justify left bottom)
				(hide yes)
			)
		)
		(property "Val" "4x10k_0201"
			(at 195.58 226.06 0)
			(effects
				(font
					(size 1.27 1.27)
					(thickness 0.15)
				)
			)
		)
		(property "Author" "Antmicro"
			(at 217.17 252.73 0)
			(effects
				(font
					(size 1.27 1.27)
					(thickness 0.15)
				)
				(justify left bottom)
				(hide yes)
			)
		)
		(property "License" "Apache-2.0"
			(at 217.17 255.27 0)
			(effects
				(font
					(size 1.27 1.27)
					(thickness 0.15)
				)
				(justify left bottom)
				(hide yes)
			)
		)
		(pin "1"
		)
		(pin "2"
		)
		(pin "3"
		)
		(pin "4"
		)
		(pin "5"
		)
		(pin "6"
		)
		(pin "7"
		)
		(pin "8"
		)
		(instances
			(project "k410t-devboard"
				(path ""
					(reference "R36")
					(unit 1)
				)
			)
		)
	)
	(symbol
		(lib_id "antmicroResistorNetworksArrays:4x39R_0201_array")
		(at 359.41 104.14 0)
		(unit 1)
		(exclude_from_sim no)
		(in_bom yes)
		(on_board yes)
		(dnp no)
		(fields_autoplaced yes)
		(property "Reference" "R17"
			(at 364.49 116.205 0)
			(effects
				(font
					(size 1.27 1.27)
				)
			)
		)
		(property "Value" "4x39R_0201_array"
			(at 386.08 109.855 0)
			(effects
				(font
					(size 1.27 1.27)
					(thickness 0.15)
				)
				(justify left bottom)
				(hide yes)
			)
		)
		(property "Footprint" "antmicro-footprints:R_Array_4x0201_Panasonic_EXB18V"
			(at 386.08 114.935 0)
			(effects
				(font
					(size 1.27 1.27)
					(thickness 0.15)
				)
				(justify left bottom)
				(hide yes)
			)
		)
		(property "Datasheet" "https://eu.mouser.com/datasheet/2/315/AOC0000C14-1108062.pdf"
			(at 386.08 117.475 0)
			(effects
				(font
					(size 1.27 1.27)
					(thickness 0.15)
				)
				(justify left bottom)
				(hide yes)
			)
		)
		(property "Description" ""
			(at 359.41 104.14 0)
			(effects
				(font
					(size 1.27 1.27)
				)
			)
		)
		(property "MPN" "EXB-18V390JX"
			(at 386.08 120.015 0)
			(effects
				(font
					(size 1.27 1.27)
					(thickness 0.15)
				)
				(justify left bottom)
				(hide yes)
			)
		)
		(property "Manufacturer" "Panasonic"
			(at 386.08 122.555 0)
			(effects
				(font
					(size 1.27 1.27)
					(thickness 0.15)
				)
				(justify left bottom)
				(hide yes)
			)
		)
		(property "Author" "Antmicro"
			(at 386.08 125.095 0)
			(effects
				(font
					(size 1.27 1.27)
					(thickness 0.15)
				)
				(justify left bottom)
				(hide yes)
			)
		)
		(property "License" "Apache-2.0"
			(at 386.08 127.635 0)
			(effects
				(font
					(size 1.27 1.27)
					(thickness 0.15)
				)
				(justify left bottom)
				(hide yes)
			)
		)
		(property "Val" "4x39R_0201"
			(at 364.49 118.745 0)
			(effects
				(font
					(size 1.27 1.27)
				)
			)
		)
		(pin "1"
		)
		(pin "2"
		)
		(pin "3"
		)
		(pin "4"
		)
		(pin "5"
		)
		(pin "6"
		)
		(pin "7"
		)
		(pin "8"
		)
		(instances
			(project "k410t-devboard"
				(path ""
					(reference "R17")
					(unit 1)
				)
			)
		)
	)
	(symbol
		(lib_id "antmicroCapacitors0402:C_100n_0402")
		(at 187.96 33.02 90)
		(unit 1)
		(exclude_from_sim no)
		(in_bom yes)
		(on_board yes)
		(dnp no)
		(property "Reference" "C183"
			(at 188.595 28.575 90)
			(effects
				(font
					(size 1.27 1.27)
				)
				(justify right)
			)
		)
		(property "Value" "C_100n_0402"
			(at 198.12 12.7 0)
			(effects
				(font
					(size 1.27 1.27)
					(thickness 0.15)
				)
				(justify left bottom)
				(hide yes)
			)
		)
		(property "Footprint" "antmicro-footprints:C_0402_1005Metric"
			(at 200.66 12.7 0)
			(effects
				(font
					(size 1.27 1.27)
					(thickness 0.15)
				)
				(justify left bottom)
				(hide yes)
			)
		)
		(property "Datasheet" "https://www.murata.com/products/productdetail?partno=GRM155R61H104KE14%23"
			(at 203.2 12.7 0)
			(effects
				(font
					(size 1.27 1.27)
					(thickness 0.15)
				)
				(justify left bottom)
				(hide yes)
			)
		)
		(property "Description" ""
			(at 187.96 33.02 0)
			(effects
				(font
					(size 1.27 1.27)
				)
			)
		)
		(property "Manufacturer" "Murata"
			(at 208.28 12.7 0)
			(effects
				(font
					(size 1.27 1.27)
					(thickness 0.15)
				)
				(justify left bottom)
				(hide yes)
			)
		)
		(property "MPN" "GRM155R61H104KE14D"
			(at 205.74 12.7 0)
			(effects
				(font
					(size 1.27 1.27)
					(thickness 0.15)
				)
				(justify left bottom)
				(hide yes)
			)
		)
		(property "Val" "100n"
			(at 188.595 32.385 90)
			(effects
				(font
					(size 1.27 1.27)
					(thickness 0.15)
				)
				(justify right)
			)
		)
		(property "License" "Apache-2.0"
			(at 210.82 12.7 0)
			(effects
				(font
					(size 1.27 1.27)
					(thickness 0.15)
				)
				(justify left bottom)
				(hide yes)
			)
		)
		(property "Author" "Antmicro"
			(at 213.36 12.7 0)
			(effects
				(font
					(size 1.27 1.27)
					(thickness 0.15)
				)
				(justify left bottom)
				(hide yes)
			)
		)
		(property "Voltage" "50V"
			(at 215.9 12.7 0)
			(effects
				(font
					(size 1.27 1.27)
				)
				(justify left bottom)
				(hide yes)
			)
		)
		(property "Dielectric" "X5R"
			(at 218.44 12.7 0)
			(effects
				(font
					(size 1.27 1.27)
				)
				(justify left bottom)
				(hide yes)
			)
		)
		(pin "1"
		)
		(pin "2"
		)
		(instances
			(project "k410t-devboard"
				(path ""
					(reference "C183")
					(unit 1)
				)
			)
		)
	)
	(symbol
		(lib_id "antmicropower:GND")
		(at 275.59 35.56 0)
		(unit 1)
		(exclude_from_sim no)
		(in_bom yes)
		(on_board yes)
		(dnp no)
		(property "Reference" "#PWR086"
			(at 275.59 41.91 0)
			(effects
				(font
					(size 1.27 1.27)
				)
				(hide yes)
			)
		)
		(property "Value" "GND"
			(at 275.59 39.37 0)
			(effects
				(font
					(size 1.27 1.27)
				)
			)
		)
		(property "Footprint" ""
			(at 284.48 43.18 0)
			(effects
				(font
					(size 1.27 1.27)
					(thickness 0.15)
				)
				(justify left bottom)
				(hide yes)
			)
		)
		(property "Datasheet" ""
			(at 284.48 48.26 0)
			(effects
				(font
					(size 1.27 1.27)
					(thickness 0.15)
				)
				(justify left bottom)
				(hide yes)
			)
		)
		(property "Description" ""
			(at 275.59 35.56 0)
			(effects
				(font
					(size 1.27 1.27)
				)
			)
		)
		(property "Author" "Antmicro"
			(at 284.48 43.18 0)
			(effects
				(font
					(size 1.27 1.27)
					(thickness 0.15)
				)
				(justify left bottom)
				(hide yes)
			)
		)
		(property "License" "Apache-2.0"
			(at 284.48 45.72 0)
			(effects
				(font
					(size 1.27 1.27)
					(thickness 0.15)
				)
				(justify left bottom)
				(hide yes)
			)
		)
		(pin "1"
		)
		(instances
			(project "k410t-devboard"
				(path ""
					(reference "#PWR086")
					(unit 1)
				)
			)
		)
	)
	(symbol
		(lib_id "antmicropower:GND")
		(at 187.96 35.56 0)
		(unit 1)
		(exclude_from_sim no)
		(in_bom yes)
		(on_board yes)
		(dnp no)
		(property "Reference" "#PWR070"
			(at 187.96 41.91 0)
			(effects
				(font
					(size 1.27 1.27)
				)
				(hide yes)
			)
		)
		(property "Value" "GND"
			(at 187.96 39.37 0)
			(effects
				(font
					(size 1.27 1.27)
				)
			)
		)
		(property "Footprint" ""
			(at 196.85 43.18 0)
			(effects
				(font
					(size 1.27 1.27)
					(thickness 0.15)
				)
				(justify left bottom)
				(hide yes)
			)
		)
		(property "Datasheet" ""
			(at 196.85 48.26 0)
			(effects
				(font
					(size 1.27 1.27)
					(thickness 0.15)
				)
				(justify left bottom)
				(hide yes)
			)
		)
		(property "Description" ""
			(at 187.96 35.56 0)
			(effects
				(font
					(size 1.27 1.27)
				)
			)
		)
		(property "Author" "Antmicro"
			(at 196.85 43.18 0)
			(effects
				(font
					(size 1.27 1.27)
					(thickness 0.15)
				)
				(justify left bottom)
				(hide yes)
			)
		)
		(property "License" "Apache-2.0"
			(at 196.85 45.72 0)
			(effects
				(font
					(size 1.27 1.27)
					(thickness 0.15)
				)
				(justify left bottom)
				(hide yes)
			)
		)
		(pin "1"
		)
		(instances
			(project "k410t-devboard"
				(path ""
					(reference "#PWR070")
					(unit 1)
				)
			)
		)
	)
	(symbol
		(lib_id "antmicropower:GND")
		(at 170.18 35.56 0)
		(unit 1)
		(exclude_from_sim no)
		(in_bom yes)
		(on_board yes)
		(dnp no)
		(property "Reference" "#PWR068"
			(at 170.18 41.91 0)
			(effects
				(font
					(size 1.27 1.27)
				)
				(hide yes)
			)
		)
		(property "Value" "GND"
			(at 170.18 39.37 0)
			(effects
				(font
					(size 1.27 1.27)
				)
			)
		)
		(property "Footprint" ""
			(at 179.07 43.18 0)
			(effects
				(font
					(size 1.27 1.27)
					(thickness 0.15)
				)
				(justify left bottom)
				(hide yes)
			)
		)
		(property "Datasheet" ""
			(at 179.07 48.26 0)
			(effects
				(font
					(size 1.27 1.27)
					(thickness 0.15)
				)
				(justify left bottom)
				(hide yes)
			)
		)
		(property "Description" ""
			(at 170.18 35.56 0)
			(effects
				(font
					(size 1.27 1.27)
				)
			)
		)
		(property "Author" "Antmicro"
			(at 179.07 43.18 0)
			(effects
				(font
					(size 1.27 1.27)
					(thickness 0.15)
				)
				(justify left bottom)
				(hide yes)
			)
		)
		(property "License" "Apache-2.0"
			(at 179.07 45.72 0)
			(effects
				(font
					(size 1.27 1.27)
					(thickness 0.15)
				)
				(justify left bottom)
				(hide yes)
			)
		)
		(pin "1"
		)
		(instances
			(project "k410t-devboard"
				(path ""
					(reference "#PWR068")
					(unit 1)
				)
			)
		)
	)
	(symbol
		(lib_id "antmicroCapacitors0402:C_100n_0402")
		(at 161.29 33.02 90)
		(unit 1)
		(exclude_from_sim no)
		(in_bom yes)
		(on_board yes)
		(dnp no)
		(property "Reference" "C179"
			(at 161.925 28.575 90)
			(effects
				(font
					(size 1.27 1.27)
				)
				(justify right)
			)
		)
		(property "Value" "C_100n_0402"
			(at 171.45 12.7 0)
			(effects
				(font
					(size 1.27 1.27)
					(thickness 0.15)
				)
				(justify left bottom)
				(hide yes)
			)
		)
		(property "Footprint" "antmicro-footprints:C_0402_1005Metric"
			(at 173.99 12.7 0)
			(effects
				(font
					(size 1.27 1.27)
					(thickness 0.15)
				)
				(justify left bottom)
				(hide yes)
			)
		)
		(property "Datasheet" "https://www.murata.com/products/productdetail?partno=GRM155R61H104KE14%23"
			(at 176.53 12.7 0)
			(effects
				(font
					(size 1.27 1.27)
					(thickness 0.15)
				)
				(justify left bottom)
				(hide yes)
			)
		)
		(property "Description" ""
			(at 161.29 33.02 0)
			(effects
				(font
					(size 1.27 1.27)
				)
			)
		)
		(property "Manufacturer" "Murata"
			(at 181.61 12.7 0)
			(effects
				(font
					(size 1.27 1.27)
					(thickness 0.15)
				)
				(justify left bottom)
				(hide yes)
			)
		)
		(property "MPN" "GRM155R61H104KE14D"
			(at 179.07 12.7 0)
			(effects
				(font
					(size 1.27 1.27)
					(thickness 0.15)
				)
				(justify left bottom)
				(hide yes)
			)
		)
		(property "Val" "100n"
			(at 161.925 32.385 90)
			(effects
				(font
					(size 1.27 1.27)
					(thickness 0.15)
				)
				(justify right)
			)
		)
		(property "License" "Apache-2.0"
			(at 184.15 12.7 0)
			(effects
				(font
					(size 1.27 1.27)
					(thickness 0.15)
				)
				(justify left bottom)
				(hide yes)
			)
		)
		(property "Author" "Antmicro"
			(at 186.69 12.7 0)
			(effects
				(font
					(size 1.27 1.27)
					(thickness 0.15)
				)
				(justify left bottom)
				(hide yes)
			)
		)
		(property "Voltage" "50V"
			(at 189.23 12.7 0)
			(effects
				(font
					(size 1.27 1.27)
				)
				(justify left bottom)
				(hide yes)
			)
		)
		(property "Dielectric" "X5R"
			(at 191.77 12.7 0)
			(effects
				(font
					(size 1.27 1.27)
				)
				(justify left bottom)
				(hide yes)
			)
		)
		(pin "1"
		)
		(pin "2"
		)
		(instances
			(project "k410t-devboard"
				(path ""
					(reference "C179")
					(unit 1)
				)
			)
		)
	)
	(symbol
		(lib_id "antmicropower:+3.3V")
		(at 204.47 227.33 0)
		(unit 1)
		(exclude_from_sim no)
		(in_bom yes)
		(on_board yes)
		(dnp no)
		(fields_autoplaced yes)
		(property "Reference" "#PWR075"
			(at 204.47 231.14 0)
			(effects
				(font
					(size 1.27 1.27)
				)
				(hide yes)
			)
		)
		(property "Value" "+3V3"
			(at 204.47 223.774 0)
			(effects
				(font
					(size 1.27 1.27)
				)
			)
		)
		(property "Footprint" ""
			(at 204.47 227.33 0)
			(effects
				(font
					(size 1.27 1.27)
				)
				(hide yes)
			)
		)
		(property "Datasheet" ""
			(at 204.47 227.33 0)
			(effects
				(font
					(size 1.27 1.27)
				)
				(hide yes)
			)
		)
		(property "Description" ""
			(at 204.47 227.33 0)
			(effects
				(font
					(size 1.27 1.27)
				)
			)
		)
		(pin "1"
		)
		(instances
			(project "k410t-devboard"
				(path ""
					(reference "#PWR075")
					(unit 1)
				)
			)
		)
	)
	(symbol
		(lib_id "antmicropower:GND")
		(at 241.3 35.56 0)
		(unit 1)
		(exclude_from_sim no)
		(in_bom yes)
		(on_board yes)
		(dnp no)
		(property "Reference" "#PWR080"
			(at 241.3 41.91 0)
			(effects
				(font
					(size 1.27 1.27)
				)
				(hide yes)
			)
		)
		(property "Value" "GND"
			(at 241.3 39.37 0)
			(effects
				(font
					(size 1.27 1.27)
				)
			)
		)
		(property "Footprint" ""
			(at 250.19 43.18 0)
			(effects
				(font
					(size 1.27 1.27)
					(thickness 0.15)
				)
				(justify left bottom)
				(hide yes)
			)
		)
		(property "Datasheet" ""
			(at 250.19 48.26 0)
			(effects
				(font
					(size 1.27 1.27)
					(thickness 0.15)
				)
				(justify left bottom)
				(hide yes)
			)
		)
		(property "Description" ""
			(at 241.3 35.56 0)
			(effects
				(font
					(size 1.27 1.27)
				)
			)
		)
		(property "Author" "Antmicro"
			(at 250.19 43.18 0)
			(effects
				(font
					(size 1.27 1.27)
					(thickness 0.15)
				)
				(justify left bottom)
				(hide yes)
			)
		)
		(property "License" "Apache-2.0"
			(at 250.19 45.72 0)
			(effects
				(font
					(size 1.27 1.27)
					(thickness 0.15)
				)
				(justify left bottom)
				(hide yes)
			)
		)
		(pin "1"
		)
		(instances
			(project "k410t-devboard"
				(path ""
					(reference "#PWR080")
					(unit 1)
				)
			)
		)
	)
	(symbol
		(lib_id "antmicroCapacitors0402:C_100n_0402")
		(at 250.19 33.02 90)
		(unit 1)
		(exclude_from_sim no)
		(in_bom yes)
		(on_board yes)
		(dnp no)
		(property "Reference" "C391"
			(at 250.825 28.575 90)
			(effects
				(font
					(size 1.27 1.27)
				)
				(justify right)
			)
		)
		(property "Value" "C_100n_0402"
			(at 260.35 12.7 0)
			(effects
				(font
					(size 1.27 1.27)
					(thickness 0.15)
				)
				(justify left bottom)
				(hide yes)
			)
		)
		(property "Footprint" "antmicro-footprints:C_0402_1005Metric"
			(at 262.89 12.7 0)
			(effects
				(font
					(size 1.27 1.27)
					(thickness 0.15)
				)
				(justify left bottom)
				(hide yes)
			)
		)
		(property "Datasheet" "https://www.murata.com/products/productdetail?partno=GRM155R61H104KE14%23"
			(at 265.43 12.7 0)
			(effects
				(font
					(size 1.27 1.27)
					(thickness 0.15)
				)
				(justify left bottom)
				(hide yes)
			)
		)
		(property "Description" ""
			(at 250.19 33.02 0)
			(effects
				(font
					(size 1.27 1.27)
				)
			)
		)
		(property "Manufacturer" "Murata"
			(at 270.51 12.7 0)
			(effects
				(font
					(size 1.27 1.27)
					(thickness 0.15)
				)
				(justify left bottom)
				(hide yes)
			)
		)
		(property "MPN" "GRM155R61H104KE14D"
			(at 267.97 12.7 0)
			(effects
				(font
					(size 1.27 1.27)
					(thickness 0.15)
				)
				(justify left bottom)
				(hide yes)
			)
		)
		(property "Val" "100n"
			(at 250.825 32.385 90)
			(effects
				(font
					(size 1.27 1.27)
					(thickness 0.15)
				)
				(justify right)
			)
		)
		(property "License" "Apache-2.0"
			(at 273.05 12.7 0)
			(effects
				(font
					(size 1.27 1.27)
					(thickness 0.15)
				)
				(justify left bottom)
				(hide yes)
			)
		)
		(property "Author" "Antmicro"
			(at 275.59 12.7 0)
			(effects
				(font
					(size 1.27 1.27)
					(thickness 0.15)
				)
				(justify left bottom)
				(hide yes)
			)
		)
		(property "Voltage" "50V"
			(at 278.13 12.7 0)
			(effects
				(font
					(size 1.27 1.27)
				)
				(justify left bottom)
				(hide yes)
			)
		)
		(property "Dielectric" "X5R"
			(at 280.67 12.7 0)
			(effects
				(font
					(size 1.27 1.27)
				)
				(justify left bottom)
				(hide yes)
			)
		)
		(pin "1"
		)
		(pin "2"
		)
		(instances
			(project "k410t-devboard"
				(path ""
					(reference "C391")
					(unit 1)
				)
			)
		)
	)
	(symbol
		(lib_id "antmicropower:GND")
		(at 154.94 193.04 0)
		(unit 1)
		(exclude_from_sim no)
		(in_bom yes)
		(on_board yes)
		(dnp no)
		(property "Reference" "#PWR064"
			(at 154.94 199.39 0)
			(effects
				(font
					(size 1.27 1.27)
				)
				(hide yes)
			)
		)
		(property "Value" "GND"
			(at 154.94 196.85 0)
			(effects
				(font
					(size 1.27 1.27)
				)
			)
		)
		(property "Footprint" ""
			(at 163.83 200.66 0)
			(effects
				(font
					(size 1.27 1.27)
					(thickness 0.15)
				)
				(justify left bottom)
				(hide yes)
			)
		)
		(property "Datasheet" ""
			(at 163.83 205.74 0)
			(effects
				(font
					(size 1.27 1.27)
					(thickness 0.15)
				)
				(justify left bottom)
				(hide yes)
			)
		)
		(property "Description" ""
			(at 154.94 193.04 0)
			(effects
				(font
					(size 1.27 1.27)
				)
			)
		)
		(property "Author" "Antmicro"
			(at 163.83 200.66 0)
			(effects
				(font
					(size 1.27 1.27)
					(thickness 0.15)
				)
				(justify left bottom)
				(hide yes)
			)
		)
		(property "License" "Apache-2.0"
			(at 163.83 203.2 0)
			(effects
				(font
					(size 1.27 1.27)
					(thickness 0.15)
				)
				(justify left bottom)
				(hide yes)
			)
		)
		(pin "1"
		)
		(instances
			(project "k410t-devboard"
				(path ""
					(reference "#PWR064")
					(unit 1)
				)
			)
		)
	)
	(symbol
		(lib_id "antmicroCapacitors0402:C_100n_0402")
		(at 214.63 33.02 90)
		(unit 1)
		(exclude_from_sim no)
		(in_bom yes)
		(on_board yes)
		(dnp no)
		(property "Reference" "C294"
			(at 215.265 28.575 90)
			(effects
				(font
					(size 1.27 1.27)
				)
				(justify right)
			)
		)
		(property "Value" "C_100n_0402"
			(at 224.79 12.7 0)
			(effects
				(font
					(size 1.27 1.27)
					(thickness 0.15)
				)
				(justify left bottom)
				(hide yes)
			)
		)
		(property "Footprint" "antmicro-footprints:C_0402_1005Metric"
			(at 227.33 12.7 0)
			(effects
				(font
					(size 1.27 1.27)
					(thickness 0.15)
				)
				(justify left bottom)
				(hide yes)
			)
		)
		(property "Datasheet" "https://www.murata.com/products/productdetail?partno=GRM155R61H104KE14%23"
			(at 229.87 12.7 0)
			(effects
				(font
					(size 1.27 1.27)
					(thickness 0.15)
				)
				(justify left bottom)
				(hide yes)
			)
		)
		(property "Description" ""
			(at 214.63 33.02 0)
			(effects
				(font
					(size 1.27 1.27)
				)
			)
		)
		(property "Manufacturer" "Murata"
			(at 234.95 12.7 0)
			(effects
				(font
					(size 1.27 1.27)
					(thickness 0.15)
				)
				(justify left bottom)
				(hide yes)
			)
		)
		(property "MPN" "GRM155R61H104KE14D"
			(at 232.41 12.7 0)
			(effects
				(font
					(size 1.27 1.27)
					(thickness 0.15)
				)
				(justify left bottom)
				(hide yes)
			)
		)
		(property "Val" "100n"
			(at 215.265 32.385 90)
			(effects
				(font
					(size 1.27 1.27)
					(thickness 0.15)
				)
				(justify right)
			)
		)
		(property "License" "Apache-2.0"
			(at 237.49 12.7 0)
			(effects
				(font
					(size 1.27 1.27)
					(thickness 0.15)
				)
				(justify left bottom)
				(hide yes)
			)
		)
		(property "Author" "Antmicro"
			(at 240.03 12.7 0)
			(effects
				(font
					(size 1.27 1.27)
					(thickness 0.15)
				)
				(justify left bottom)
				(hide yes)
			)
		)
		(property "Voltage" "50V"
			(at 242.57 12.7 0)
			(effects
				(font
					(size 1.27 1.27)
				)
				(justify left bottom)
				(hide yes)
			)
		)
		(property "Dielectric" "X5R"
			(at 245.11 12.7 0)
			(effects
				(font
					(size 1.27 1.27)
				)
				(justify left bottom)
				(hide yes)
			)
		)
		(pin "1"
		)
		(pin "2"
		)
		(instances
			(project "k410t-devboard"
				(path ""
					(reference "C294")
					(unit 1)
				)
			)
		)
	)
	(symbol
		(lib_id "antmicropower:GND")
		(at 179.07 35.56 0)
		(unit 1)
		(exclude_from_sim no)
		(in_bom yes)
		(on_board yes)
		(dnp no)
		(property "Reference" "#PWR069"
			(at 179.07 41.91 0)
			(effects
				(font
					(size 1.27 1.27)
				)
				(hide yes)
			)
		)
		(property "Value" "GND"
			(at 179.07 39.37 0)
			(effects
				(font
					(size 1.27 1.27)
				)
			)
		)
		(property "Footprint" ""
			(at 187.96 43.18 0)
			(effects
				(font
					(size 1.27 1.27)
					(thickness 0.15)
				)
				(justify left bottom)
				(hide yes)
			)
		)
		(property "Datasheet" ""
			(at 187.96 48.26 0)
			(effects
				(font
					(size 1.27 1.27)
					(thickness 0.15)
				)
				(justify left bottom)
				(hide yes)
			)
		)
		(property "Description" ""
			(at 179.07 35.56 0)
			(effects
				(font
					(size 1.27 1.27)
				)
			)
		)
		(property "Author" "Antmicro"
			(at 187.96 43.18 0)
			(effects
				(font
					(size 1.27 1.27)
					(thickness 0.15)
				)
				(justify left bottom)
				(hide yes)
			)
		)
		(property "License" "Apache-2.0"
			(at 187.96 45.72 0)
			(effects
				(font
					(size 1.27 1.27)
					(thickness 0.15)
				)
				(justify left bottom)
				(hide yes)
			)
		)
		(pin "1"
		)
		(instances
			(project "k410t-devboard"
				(path ""
					(reference "#PWR069")
					(unit 1)
				)
			)
		)
	)
	(symbol
		(lib_id "antmicropower:+0V675_VREF")
		(at 209.55 53.34 0)
		(unit 1)
		(exclude_from_sim no)
		(in_bom yes)
		(on_board yes)
		(dnp no)
		(fields_autoplaced yes)
		(property "Reference" "#PWR082"
			(at 209.55 57.15 0)
			(effects
				(font
					(size 1.27 1.27)
				)
				(hide yes)
			)
		)
		(property "Value" "+0V675_VREF"
			(at 209.55 49.784 0)
			(effects
				(font
					(size 1.27 1.27)
				)
			)
		)
		(property "Footprint" ""
			(at 209.55 53.34 0)
			(effects
				(font
					(size 1.27 1.27)
				)
				(hide yes)
			)
		)
		(property "Datasheet" ""
			(at 209.55 53.34 0)
			(effects
				(font
					(size 1.27 1.27)
				)
				(hide yes)
			)
		)
		(property "Description" ""
			(at 209.55 53.34 0)
			(effects
				(font
					(size 1.27 1.27)
				)
			)
		)
		(pin "1"
		)
		(instances
			(project "k410t-devboard"
				(path ""
					(reference "#PWR082")
					(unit 1)
				)
			)
		)
	)
	(symbol
		(lib_id "antmicropower:+0V675_VTT")
		(at 377.19 86.36 0)
		(unit 1)
		(exclude_from_sim no)
		(in_bom yes)
		(on_board yes)
		(dnp no)
		(fields_autoplaced yes)
		(property "Reference" "#PWR0280"
			(at 377.19 90.17 0)
			(effects
				(font
					(size 1.27 1.27)
				)
				(hide yes)
			)
		)
		(property "Value" "+0V675_VTT"
			(at 377.19 82.804 0)
			(effects
				(font
					(size 1.27 1.27)
				)
			)
		)
		(property "Footprint" ""
			(at 377.19 86.36 0)
			(effects
				(font
					(size 1.27 1.27)
				)
				(hide yes)
			)
		)
		(property "Datasheet" ""
			(at 377.19 86.36 0)
			(effects
				(font
					(size 1.27 1.27)
				)
				(hide yes)
			)
		)
		(property "Description" ""
			(at 377.19 86.36 0)
			(effects
				(font
					(size 1.27 1.27)
				)
			)
		)
		(pin "1"
		)
		(instances
			(project "k410t-devboard"
				(path ""
					(reference "#PWR0280")
					(unit 1)
				)
			)
		)
	)
	(symbol
		(lib_id "antmicroResistors0402:R_10k_0402")
		(at 100.33 38.1 90)
		(unit 1)
		(exclude_from_sim no)
		(in_bom yes)
		(on_board yes)
		(dnp no)
		(property "Reference" "R34"
			(at 101.6 34.29 90)
			(effects
				(font
					(size 1.27 1.27)
				)
				(justify right)
			)
		)
		(property "Value" "R_10k_0402"
			(at 113.03 17.78 0)
			(effects
				(font
					(size 1.27 1.27)
					(thickness 0.15)
				)
				(justify left bottom)
				(hide yes)
			)
		)
		(property "Footprint" "antmicro-footprints:R_0402_1005Metric"
			(at 115.57 17.78 0)
			(effects
				(font
					(size 1.27 1.27)
					(thickness 0.15)
				)
				(justify left bottom)
				(hide yes)
			)
		)
		(property "Datasheet" "https://www.bourns.com/docs/product-datasheets/cr.pdf"
			(at 118.11 17.78 0)
			(effects
				(font
					(size 1.27 1.27)
					(thickness 0.15)
				)
				(justify left bottom)
				(hide yes)
			)
		)
		(property "Description" ""
			(at 100.33 38.1 0)
			(effects
				(font
					(size 1.27 1.27)
				)
			)
		)
		(property "Manufacturer" "Bourns"
			(at 123.19 17.78 0)
			(effects
				(font
					(size 1.27 1.27)
					(thickness 0.15)
				)
				(justify left bottom)
				(hide yes)
			)
		)
		(property "MPN" "CR0402-FX-1002GLF"
			(at 120.65 17.78 0)
			(effects
				(font
					(size 1.27 1.27)
					(thickness 0.15)
				)
				(justify left bottom)
				(hide yes)
			)
		)
		(property "Val" "10k"
			(at 101.6 36.83 90)
			(effects
				(font
					(size 1.27 1.27)
					(thickness 0.15)
				)
				(justify right)
			)
		)
		(property "License" "Apache-2.0"
			(at 125.73 17.78 0)
			(effects
				(font
					(size 1.27 1.27)
					(thickness 0.15)
				)
				(justify left bottom)
				(hide yes)
			)
		)
		(property "Author" "Antmicro"
			(at 128.27 17.78 0)
			(effects
				(font
					(size 1.27 1.27)
					(thickness 0.15)
				)
				(justify left bottom)
				(hide yes)
			)
		)
		(property "Tolerance" "1%"
			(at 110.49 17.78 0)
			(effects
				(font
					(size 1.27 1.27)
				)
				(justify left bottom)
				(hide yes)
			)
		)
		(pin "1"
		)
		(pin "2"
		)
		(instances
			(project "k410t-devboard"
				(path ""
					(reference "R34")
					(unit 1)
				)
			)
		)
	)
	(symbol
		(lib_id "antmicroCapacitors0402:C_100n_0402")
		(at 152.4 33.02 90)
		(unit 1)
		(exclude_from_sim no)
		(in_bom yes)
		(on_board yes)
		(dnp no)
		(property "Reference" "C177"
			(at 153.035 28.575 90)
			(effects
				(font
					(size 1.27 1.27)
				)
				(justify right)
			)
		)
		(property "Value" "C_100n_0402"
			(at 162.56 12.7 0)
			(effects
				(font
					(size 1.27 1.27)
					(thickness 0.15)
				)
				(justify left bottom)
				(hide yes)
			)
		)
		(property "Footprint" "antmicro-footprints:C_0402_1005Metric"
			(at 165.1 12.7 0)
			(effects
				(font
					(size 1.27 1.27)
					(thickness 0.15)
				)
				(justify left bottom)
				(hide yes)
			)
		)
		(property "Datasheet" "https://www.murata.com/products/productdetail?partno=GRM155R61H104KE14%23"
			(at 167.64 12.7 0)
			(effects
				(font
					(size 1.27 1.27)
					(thickness 0.15)
				)
				(justify left bottom)
				(hide yes)
			)
		)
		(property "Description" ""
			(at 152.4 33.02 0)
			(effects
				(font
					(size 1.27 1.27)
				)
			)
		)
		(property "Manufacturer" "Murata"
			(at 172.72 12.7 0)
			(effects
				(font
					(size 1.27 1.27)
					(thickness 0.15)
				)
				(justify left bottom)
				(hide yes)
			)
		)
		(property "MPN" "GRM155R61H104KE14D"
			(at 170.18 12.7 0)
			(effects
				(font
					(size 1.27 1.27)
					(thickness 0.15)
				)
				(justify left bottom)
				(hide yes)
			)
		)
		(property "Val" "100n"
			(at 153.035 32.385 90)
			(effects
				(font
					(size 1.27 1.27)
					(thickness 0.15)
				)
				(justify right)
			)
		)
		(property "License" "Apache-2.0"
			(at 175.26 12.7 0)
			(effects
				(font
					(size 1.27 1.27)
					(thickness 0.15)
				)
				(justify left bottom)
				(hide yes)
			)
		)
		(property "Author" "Antmicro"
			(at 177.8 12.7 0)
			(effects
				(font
					(size 1.27 1.27)
					(thickness 0.15)
				)
				(justify left bottom)
				(hide yes)
			)
		)
		(property "Voltage" "50V"
			(at 180.34 12.7 0)
			(effects
				(font
					(size 1.27 1.27)
				)
				(justify left bottom)
				(hide yes)
			)
		)
		(property "Dielectric" "X5R"
			(at 182.88 12.7 0)
			(effects
				(font
					(size 1.27 1.27)
				)
				(justify left bottom)
				(hide yes)
			)
		)
		(pin "1"
		)
		(pin "2"
		)
		(instances
			(project "k410t-devboard"
				(path ""
					(reference "C177")
					(unit 1)
				)
			)
		)
	)
	(symbol
		(lib_id "antmicropower:+0V675_VTT")
		(at 274.32 86.36 0)
		(unit 1)
		(exclude_from_sim no)
		(in_bom yes)
		(on_board yes)
		(dnp no)
		(fields_autoplaced yes)
		(property "Reference" "#PWR0448"
			(at 274.32 90.17 0)
			(effects
				(font
					(size 1.27 1.27)
				)
				(hide yes)
			)
		)
		(property "Value" "+0V675_VTT"
			(at 274.32 82.804 0)
			(effects
				(font
					(size 1.27 1.27)
				)
			)
		)
		(property "Footprint" ""
			(at 274.32 86.36 0)
			(effects
				(font
					(size 1.27 1.27)
				)
				(hide yes)
			)
		)
		(property "Datasheet" ""
			(at 274.32 86.36 0)
			(effects
				(font
					(size 1.27 1.27)
				)
				(hide yes)
			)
		)
		(property "Description" ""
			(at 274.32 86.36 0)
			(effects
				(font
					(size 1.27 1.27)
				)
			)
		)
		(pin "1"
		)
		(instances
			(project "k410t-devboard"
				(path ""
					(reference "#PWR0448")
					(unit 1)
				)
			)
		)
	)
	(symbol
		(lib_id "antmicroCapacitors0402:C_100n_0402")
		(at 146.05 191.77 90)
		(unit 1)
		(exclude_from_sim no)
		(in_bom yes)
		(on_board yes)
		(dnp no)
		(property "Reference" "C176"
			(at 146.685 187.325 90)
			(effects
				(font
					(size 1.27 1.27)
				)
				(justify right)
			)
		)
		(property "Value" "C_100n_0402"
			(at 156.21 171.45 0)
			(effects
				(font
					(size 1.27 1.27)
					(thickness 0.15)
				)
				(justify left bottom)
				(hide yes)
			)
		)
		(property "Footprint" "antmicro-footprints:C_0402_1005Metric"
			(at 158.75 171.45 0)
			(effects
				(font
					(size 1.27 1.27)
					(thickness 0.15)
				)
				(justify left bottom)
				(hide yes)
			)
		)
		(property "Datasheet" "https://www.murata.com/products/productdetail?partno=GRM155R61H104KE14%23"
			(at 161.29 171.45 0)
			(effects
				(font
					(size 1.27 1.27)
					(thickness 0.15)
				)
				(justify left bottom)
				(hide yes)
			)
		)
		(property "Description" ""
			(at 146.05 191.77 0)
			(effects
				(font
					(size 1.27 1.27)
				)
			)
		)
		(property "Manufacturer" "Murata"
			(at 166.37 171.45 0)
			(effects
				(font
					(size 1.27 1.27)
					(thickness 0.15)
				)
				(justify left bottom)
				(hide yes)
			)
		)
		(property "MPN" "GRM155R61H104KE14D"
			(at 163.83 171.45 0)
			(effects
				(font
					(size 1.27 1.27)
					(thickness 0.15)
				)
				(justify left bottom)
				(hide yes)
			)
		)
		(property "Val" "100n"
			(at 146.685 191.135 90)
			(effects
				(font
					(size 1.27 1.27)
					(thickness 0.15)
				)
				(justify right)
			)
		)
		(property "License" "Apache-2.0"
			(at 168.91 171.45 0)
			(effects
				(font
					(size 1.27 1.27)
					(thickness 0.15)
				)
				(justify left bottom)
				(hide yes)
			)
		)
		(property "Author" "Antmicro"
			(at 171.45 171.45 0)
			(effects
				(font
					(size 1.27 1.27)
					(thickness 0.15)
				)
				(justify left bottom)
				(hide yes)
			)
		)
		(property "Voltage" "50V"
			(at 173.99 171.45 0)
			(effects
				(font
					(size 1.27 1.27)
				)
				(justify left bottom)
				(hide yes)
			)
		)
		(property "Dielectric" "X5R"
			(at 176.53 171.45 0)
			(effects
				(font
					(size 1.27 1.27)
				)
				(justify left bottom)
				(hide yes)
			)
		)
		(pin "1"
		)
		(pin "2"
		)
		(instances
			(project "k410t-devboard"
				(path ""
					(reference "C176")
					(unit 1)
				)
			)
		)
	)
	(symbol
		(lib_id "antmicropower:GND")
		(at 168.91 193.04 0)
		(unit 1)
		(exclude_from_sim no)
		(in_bom yes)
		(on_board yes)
		(dnp no)
		(property "Reference" "#PWR067"
			(at 168.91 199.39 0)
			(effects
				(font
					(size 1.27 1.27)
				)
				(hide yes)
			)
		)
		(property "Value" "GND"
			(at 168.91 196.85 0)
			(effects
				(font
					(size 1.27 1.27)
				)
			)
		)
		(property "Footprint" ""
			(at 177.8 200.66 0)
			(effects
				(font
					(size 1.27 1.27)
					(thickness 0.15)
				)
				(justify left bottom)
				(hide yes)
			)
		)
		(property "Datasheet" ""
			(at 177.8 205.74 0)
			(effects
				(font
					(size 1.27 1.27)
					(thickness 0.15)
				)
				(justify left bottom)
				(hide yes)
			)
		)
		(property "Description" ""
			(at 168.91 193.04 0)
			(effects
				(font
					(size 1.27 1.27)
				)
			)
		)
		(property "Author" "Antmicro"
			(at 177.8 200.66 0)
			(effects
				(font
					(size 1.27 1.27)
					(thickness 0.15)
				)
				(justify left bottom)
				(hide yes)
			)
		)
		(property "License" "Apache-2.0"
			(at 177.8 203.2 0)
			(effects
				(font
					(size 1.27 1.27)
					(thickness 0.15)
				)
				(justify left bottom)
				(hide yes)
			)
		)
		(pin "1"
		)
		(instances
			(project "k410t-devboard"
				(path ""
					(reference "#PWR067")
					(unit 1)
				)
			)
		)
	)
	(symbol
		(lib_id "antmicroCapacitors0402:C_100n_0402")
		(at 179.07 33.02 90)
		(unit 1)
		(exclude_from_sim no)
		(in_bom yes)
		(on_board yes)
		(dnp no)
		(property "Reference" "C182"
			(at 179.705 28.575 90)
			(effects
				(font
					(size 1.27 1.27)
				)
				(justify right)
			)
		)
		(property "Value" "C_100n_0402"
			(at 189.23 12.7 0)
			(effects
				(font
					(size 1.27 1.27)
					(thickness 0.15)
				)
				(justify left bottom)
				(hide yes)
			)
		)
		(property "Footprint" "antmicro-footprints:C_0402_1005Metric"
			(at 191.77 12.7 0)
			(effects
				(font
					(size 1.27 1.27)
					(thickness 0.15)
				)
				(justify left bottom)
				(hide yes)
			)
		)
		(property "Datasheet" "https://www.murata.com/products/productdetail?partno=GRM155R61H104KE14%23"
			(at 194.31 12.7 0)
			(effects
				(font
					(size 1.27 1.27)
					(thickness 0.15)
				)
				(justify left bottom)
				(hide yes)
			)
		)
		(property "Description" ""
			(at 179.07 33.02 0)
			(effects
				(font
					(size 1.27 1.27)
				)
			)
		)
		(property "Manufacturer" "Murata"
			(at 199.39 12.7 0)
			(effects
				(font
					(size 1.27 1.27)
					(thickness 0.15)
				)
				(justify left bottom)
				(hide yes)
			)
		)
		(property "MPN" "GRM155R61H104KE14D"
			(at 196.85 12.7 0)
			(effects
				(font
					(size 1.27 1.27)
					(thickness 0.15)
				)
				(justify left bottom)
				(hide yes)
			)
		)
		(property "Val" "100n"
			(at 179.705 32.385 90)
			(effects
				(font
					(size 1.27 1.27)
					(thickness 0.15)
				)
				(justify right)
			)
		)
		(property "License" "Apache-2.0"
			(at 201.93 12.7 0)
			(effects
				(font
					(size 1.27 1.27)
					(thickness 0.15)
				)
				(justify left bottom)
				(hide yes)
			)
		)
		(property "Author" "Antmicro"
			(at 204.47 12.7 0)
			(effects
				(font
					(size 1.27 1.27)
					(thickness 0.15)
				)
				(justify left bottom)
				(hide yes)
			)
		)
		(property "Voltage" "50V"
			(at 207.01 12.7 0)
			(effects
				(font
					(size 1.27 1.27)
				)
				(justify left bottom)
				(hide yes)
			)
		)
		(property "Dielectric" "X5R"
			(at 209.55 12.7 0)
			(effects
				(font
					(size 1.27 1.27)
				)
				(justify left bottom)
				(hide yes)
			)
		)
		(pin "1"
		)
		(pin "2"
		)
		(instances
			(project "k410t-devboard"
				(path ""
					(reference "C182")
					(unit 1)
				)
			)
		)
	)
	(symbol
		(lib_id "antmicroCapacitors0402:C_100n_0402")
		(at 187.96 60.96 90)
		(unit 1)
		(exclude_from_sim no)
		(in_bom yes)
		(on_board yes)
		(dnp no)
		(property "Reference" "C184"
			(at 188.595 56.515 90)
			(effects
				(font
					(size 1.27 1.27)
				)
				(justify right)
			)
		)
		(property "Value" "C_100n_0402"
			(at 198.12 40.64 0)
			(effects
				(font
					(size 1.27 1.27)
					(thickness 0.15)
				)
				(justify left bottom)
				(hide yes)
			)
		)
		(property "Footprint" "antmicro-footprints:C_0402_1005Metric"
			(at 200.66 40.64 0)
			(effects
				(font
					(size 1.27 1.27)
					(thickness 0.15)
				)
				(justify left bottom)
				(hide yes)
			)
		)
		(property "Datasheet" "https://www.murata.com/products/productdetail?partno=GRM155R61H104KE14%23"
			(at 203.2 40.64 0)
			(effects
				(font
					(size 1.27 1.27)
					(thickness 0.15)
				)
				(justify left bottom)
				(hide yes)
			)
		)
		(property "Description" ""
			(at 187.96 60.96 0)
			(effects
				(font
					(size 1.27 1.27)
				)
			)
		)
		(property "Manufacturer" "Murata"
			(at 208.28 40.64 0)
			(effects
				(font
					(size 1.27 1.27)
					(thickness 0.15)
				)
				(justify left bottom)
				(hide yes)
			)
		)
		(property "MPN" "GRM155R61H104KE14D"
			(at 205.74 40.64 0)
			(effects
				(font
					(size 1.27 1.27)
					(thickness 0.15)
				)
				(justify left bottom)
				(hide yes)
			)
		)
		(property "Val" "100n"
			(at 188.595 60.325 90)
			(effects
				(font
					(size 1.27 1.27)
					(thickness 0.15)
				)
				(justify right)
			)
		)
		(property "License" "Apache-2.0"
			(at 210.82 40.64 0)
			(effects
				(font
					(size 1.27 1.27)
					(thickness 0.15)
				)
				(justify left bottom)
				(hide yes)
			)
		)
		(property "Author" "Antmicro"
			(at 213.36 40.64 0)
			(effects
				(font
					(size 1.27 1.27)
					(thickness 0.15)
				)
				(justify left bottom)
				(hide yes)
			)
		)
		(property "Voltage" "50V"
			(at 215.9 40.64 0)
			(effects
				(font
					(size 1.27 1.27)
				)
				(justify left bottom)
				(hide yes)
			)
		)
		(property "Dielectric" "X5R"
			(at 218.44 40.64 0)
			(effects
				(font
					(size 1.27 1.27)
				)
				(justify left bottom)
				(hide yes)
			)
		)
		(pin "1"
		)
		(pin "2"
		)
		(instances
			(project "k410t-devboard"
				(path ""
					(reference "C184")
					(unit 1)
				)
			)
		)
	)
	(symbol
		(lib_id "antmicroCapacitors0402:C_100n_0402")
		(at 232.41 33.02 90)
		(unit 1)
		(exclude_from_sim no)
		(in_bom yes)
		(on_board yes)
		(dnp no)
		(property "Reference" "C389"
			(at 233.045 28.575 90)
			(effects
				(font
					(size 1.27 1.27)
				)
				(justify right)
			)
		)
		(property "Value" "C_100n_0402"
			(at 242.57 12.7 0)
			(effects
				(font
					(size 1.27 1.27)
					(thickness 0.15)
				)
				(justify left bottom)
				(hide yes)
			)
		)
		(property "Footprint" "antmicro-footprints:C_0402_1005Metric"
			(at 245.11 12.7 0)
			(effects
				(font
					(size 1.27 1.27)
					(thickness 0.15)
				)
				(justify left bottom)
				(hide yes)
			)
		)
		(property "Datasheet" "https://www.murata.com/products/productdetail?partno=GRM155R61H104KE14%23"
			(at 247.65 12.7 0)
			(effects
				(font
					(size 1.27 1.27)
					(thickness 0.15)
				)
				(justify left bottom)
				(hide yes)
			)
		)
		(property "Description" ""
			(at 232.41 33.02 0)
			(effects
				(font
					(size 1.27 1.27)
				)
			)
		)
		(property "Manufacturer" "Murata"
			(at 252.73 12.7 0)
			(effects
				(font
					(size 1.27 1.27)
					(thickness 0.15)
				)
				(justify left bottom)
				(hide yes)
			)
		)
		(property "MPN" "GRM155R61H104KE14D"
			(at 250.19 12.7 0)
			(effects
				(font
					(size 1.27 1.27)
					(thickness 0.15)
				)
				(justify left bottom)
				(hide yes)
			)
		)
		(property "Val" "100n"
			(at 233.045 32.385 90)
			(effects
				(font
					(size 1.27 1.27)
					(thickness 0.15)
				)
				(justify right)
			)
		)
		(property "License" "Apache-2.0"
			(at 255.27 12.7 0)
			(effects
				(font
					(size 1.27 1.27)
					(thickness 0.15)
				)
				(justify left bottom)
				(hide yes)
			)
		)
		(property "Author" "Antmicro"
			(at 257.81 12.7 0)
			(effects
				(font
					(size 1.27 1.27)
					(thickness 0.15)
				)
				(justify left bottom)
				(hide yes)
			)
		)
		(property "Voltage" "50V"
			(at 260.35 12.7 0)
			(effects
				(font
					(size 1.27 1.27)
				)
				(justify left bottom)
				(hide yes)
			)
		)
		(property "Dielectric" "X5R"
			(at 262.89 12.7 0)
			(effects
				(font
					(size 1.27 1.27)
				)
				(justify left bottom)
				(hide yes)
			)
		)
		(pin "1"
		)
		(pin "2"
		)
		(instances
			(project "k410t-devboard"
				(path ""
					(reference "C389")
					(unit 1)
				)
			)
		)
	)
	(symbol
		(lib_id "antmicroCapacitors0402:C_100n_0402")
		(at 170.18 33.02 90)
		(unit 1)
		(exclude_from_sim no)
		(in_bom yes)
		(on_board yes)
		(dnp no)
		(property "Reference" "C181"
			(at 170.815 28.575 90)
			(effects
				(font
					(size 1.27 1.27)
				)
				(justify right)
			)
		)
		(property "Value" "C_100n_0402"
			(at 180.34 12.7 0)
			(effects
				(font
					(size 1.27 1.27)
					(thickness 0.15)
				)
				(justify left bottom)
				(hide yes)
			)
		)
		(property "Footprint" "antmicro-footprints:C_0402_1005Metric"
			(at 182.88 12.7 0)
			(effects
				(font
					(size 1.27 1.27)
					(thickness 0.15)
				)
				(justify left bottom)
				(hide yes)
			)
		)
		(property "Datasheet" "https://www.murata.com/products/productdetail?partno=GRM155R61H104KE14%23"
			(at 185.42 12.7 0)
			(effects
				(font
					(size 1.27 1.27)
					(thickness 0.15)
				)
				(justify left bottom)
				(hide yes)
			)
		)
		(property "Description" ""
			(at 170.18 33.02 0)
			(effects
				(font
					(size 1.27 1.27)
				)
			)
		)
		(property "Manufacturer" "Murata"
			(at 190.5 12.7 0)
			(effects
				(font
					(size 1.27 1.27)
					(thickness 0.15)
				)
				(justify left bottom)
				(hide yes)
			)
		)
		(property "MPN" "GRM155R61H104KE14D"
			(at 187.96 12.7 0)
			(effects
				(font
					(size 1.27 1.27)
					(thickness 0.15)
				)
				(justify left bottom)
				(hide yes)
			)
		)
		(property "Val" "100n"
			(at 170.815 32.385 90)
			(effects
				(font
					(size 1.27 1.27)
					(thickness 0.15)
				)
				(justify right)
			)
		)
		(property "License" "Apache-2.0"
			(at 193.04 12.7 0)
			(effects
				(font
					(size 1.27 1.27)
					(thickness 0.15)
				)
				(justify left bottom)
				(hide yes)
			)
		)
		(property "Author" "Antmicro"
			(at 195.58 12.7 0)
			(effects
				(font
					(size 1.27 1.27)
					(thickness 0.15)
				)
				(justify left bottom)
				(hide yes)
			)
		)
		(property "Voltage" "50V"
			(at 198.12 12.7 0)
			(effects
				(font
					(size 1.27 1.27)
				)
				(justify left bottom)
				(hide yes)
			)
		)
		(property "Dielectric" "X5R"
			(at 200.66 12.7 0)
			(effects
				(font
					(size 1.27 1.27)
				)
				(justify left bottom)
				(hide yes)
			)
		)
		(pin "1"
		)
		(pin "2"
		)
		(instances
			(project "k410t-devboard"
				(path ""
					(reference "C181")
					(unit 1)
				)
			)
		)
	)
	(symbol
		(lib_id "antmicropower:GND")
		(at 205.74 35.56 0)
		(unit 1)
		(exclude_from_sim no)
		(in_bom yes)
		(on_board yes)
		(dnp no)
		(property "Reference" "#PWR076"
			(at 205.74 41.91 0)
			(effects
				(font
					(size 1.27 1.27)
				)
				(hide yes)
			)
		)
		(property "Value" "GND"
			(at 205.74 39.37 0)
			(effects
				(font
					(size 1.27 1.27)
				)
			)
		)
		(property "Footprint" ""
			(at 214.63 43.18 0)
			(effects
				(font
					(size 1.27 1.27)
					(thickness 0.15)
				)
				(justify left bottom)
				(hide yes)
			)
		)
		(property "Datasheet" ""
			(at 214.63 48.26 0)
			(effects
				(font
					(size 1.27 1.27)
					(thickness 0.15)
				)
				(justify left bottom)
				(hide yes)
			)
		)
		(property "Description" ""
			(at 205.74 35.56 0)
			(effects
				(font
					(size 1.27 1.27)
				)
			)
		)
		(property "Author" "Antmicro"
			(at 214.63 43.18 0)
			(effects
				(font
					(size 1.27 1.27)
					(thickness 0.15)
				)
				(justify left bottom)
				(hide yes)
			)
		)
		(property "License" "Apache-2.0"
			(at 214.63 45.72 0)
			(effects
				(font
					(size 1.27 1.27)
					(thickness 0.15)
				)
				(justify left bottom)
				(hide yes)
			)
		)
		(pin "1"
		)
		(instances
			(project "k410t-devboard"
				(path ""
					(reference "#PWR076")
					(unit 1)
				)
			)
		)
	)
	(symbol
		(lib_id "antmicroResistors0402:R_40R2_0402")
		(at 213.36 91.44 0)
		(unit 1)
		(exclude_from_sim no)
		(in_bom yes)
		(on_board yes)
		(dnp no)
		(property "Reference" "R43"
			(at 220.345 90.17 0)
			(effects
				(font
					(size 1.27 1.27)
				)
			)
		)
		(property "Value" "R_40R2_0402"
			(at 233.68 104.14 0)
			(effects
				(font
					(size 1.27 1.27)
					(thickness 0.15)
				)
				(justify left bottom)
				(hide yes)
			)
		)
		(property "Footprint" "antmicro-footprints:R_0402_1005Metric"
			(at 233.68 106.68 0)
			(effects
				(font
					(size 1.27 1.27)
					(thickness 0.15)
				)
				(justify left bottom)
				(hide yes)
			)
		)
		(property "Datasheet" "https://www.bourns.com/docs/product-datasheets/cr.pdf"
			(at 233.68 109.22 0)
			(effects
				(font
					(size 1.27 1.27)
					(thickness 0.15)
				)
				(justify left bottom)
				(hide yes)
			)
		)
		(property "Description" ""
			(at 213.36 91.44 0)
			(effects
				(font
					(size 1.27 1.27)
				)
			)
		)
		(property "Manufacturer" "Bourns"
			(at 233.68 114.3 0)
			(effects
				(font
					(size 1.27 1.27)
					(thickness 0.15)
				)
				(justify left bottom)
				(hide yes)
			)
		)
		(property "MPN" "CR0402-FX-40R2GLF"
			(at 233.68 111.76 0)
			(effects
				(font
					(size 1.27 1.27)
					(thickness 0.15)
				)
				(justify left bottom)
				(hide yes)
			)
		)
		(property "Val" "40R2"
			(at 210.82 90.17 0)
			(effects
				(font
					(size 1.27 1.27)
					(thickness 0.15)
				)
			)
		)
		(property "License" "Apache-2.0"
			(at 233.68 116.84 0)
			(effects
				(font
					(size 1.27 1.27)
					(thickness 0.15)
				)
				(justify left bottom)
				(hide yes)
			)
		)
		(property "Author" "Antmicro"
			(at 233.68 119.38 0)
			(effects
				(font
					(size 1.27 1.27)
					(thickness 0.15)
				)
				(justify left bottom)
				(hide yes)
			)
		)
		(property "Tolerance" "1%"
			(at 233.68 101.6 0)
			(effects
				(font
					(size 1.27 1.27)
				)
				(justify left bottom)
				(hide yes)
			)
		)
		(pin "1"
		)
		(pin "2"
		)
		(instances
			(project "k410t-devboard"
				(path ""
					(reference "R43")
					(unit 1)
				)
			)
		)
	)
	(symbol
		(lib_id "antmicroCapacitors0402:C_10u_0402")
		(at 168.91 191.77 90)
		(unit 1)
		(exclude_from_sim no)
		(in_bom yes)
		(on_board yes)
		(dnp no)
		(property "Reference" "C180"
			(at 169.545 187.325 90)
			(effects
				(font
					(size 1.27 1.27)
				)
				(justify right)
			)
		)
		(property "Value" "C_10u_0402"
			(at 179.07 171.45 0)
			(effects
				(font
					(size 1.27 1.27)
					(thickness 0.15)
				)
				(justify left bottom)
				(hide yes)
			)
		)
		(property "Footprint" "antmicro-footprints:C_0402_1005Metric"
			(at 181.61 171.45 0)
			(effects
				(font
					(size 1.27 1.27)
					(thickness 0.15)
				)
				(justify left bottom)
				(hide yes)
			)
		)
		(property "Datasheet" "https://www.yageo.com/en/Chart/Download/pdf/CC0402MRX5R5BB106"
			(at 184.15 171.45 0)
			(effects
				(font
					(size 1.27 1.27)
					(thickness 0.15)
				)
				(justify left bottom)
				(hide yes)
			)
		)
		(property "Description" ""
			(at 168.91 191.77 0)
			(effects
				(font
					(size 1.27 1.27)
				)
			)
		)
		(property "Manufacturer" "YAGEO"
			(at 189.23 171.45 0)
			(effects
				(font
					(size 1.27 1.27)
					(thickness 0.15)
				)
				(justify left bottom)
				(hide yes)
			)
		)
		(property "MPN" "CC0402MRX5R5BB106"
			(at 186.69 171.45 0)
			(effects
				(font
					(size 1.27 1.27)
					(thickness 0.15)
				)
				(justify left bottom)
				(hide yes)
			)
		)
		(property "Val" "10u"
			(at 169.545 191.135 90)
			(effects
				(font
					(size 1.27 1.27)
					(thickness 0.15)
				)
				(justify right)
			)
		)
		(property "License" "Apache-2.0"
			(at 191.77 171.45 0)
			(effects
				(font
					(size 1.27 1.27)
					(thickness 0.15)
				)
				(justify left bottom)
				(hide yes)
			)
		)
		(property "Author" "Antmicro"
			(at 194.31 171.45 0)
			(effects
				(font
					(size 1.27 1.27)
					(thickness 0.15)
				)
				(justify left bottom)
				(hide yes)
			)
		)
		(property "Voltage" ""
			(at 196.85 171.45 0)
			(effects
				(font
					(size 1.27 1.27)
				)
				(justify left bottom)
				(hide yes)
			)
		)
		(property "Dielectric" ""
			(at 199.39 171.45 0)
			(effects
				(font
					(size 1.27 1.27)
				)
				(justify left bottom)
				(hide yes)
			)
		)
		(pin "1"
		)
		(pin "2"
		)
		(instances
			(project "k410t-devboard"
				(path ""
					(reference "C180")
					(unit 1)
				)
			)
		)
	)
	(symbol
		(lib_id "antmicropower:GND")
		(at 100.33 39.37 0)
		(unit 1)
		(exclude_from_sim no)
		(in_bom yes)
		(on_board yes)
		(dnp no)
		(property "Reference" "#PWR057"
			(at 100.33 45.72 0)
			(effects
				(font
					(size 1.27 1.27)
				)
				(hide yes)
			)
		)
		(property "Value" "GND"
			(at 100.33 43.18 0)
			(effects
				(font
					(size 1.27 1.27)
				)
			)
		)
		(property "Footprint" ""
			(at 109.22 46.99 0)
			(effects
				(font
					(size 1.27 1.27)
					(thickness 0.15)
				)
				(justify left bottom)
				(hide yes)
			)
		)
		(property "Datasheet" ""
			(at 109.22 52.07 0)
			(effects
				(font
					(size 1.27 1.27)
					(thickness 0.15)
				)
				(justify left bottom)
				(hide yes)
			)
		)
		(property "Description" ""
			(at 100.33 39.37 0)
			(effects
				(font
					(size 1.27 1.27)
				)
			)
		)
		(property "Author" "Antmicro"
			(at 109.22 46.99 0)
			(effects
				(font
					(size 1.27 1.27)
					(thickness 0.15)
				)
				(justify left bottom)
				(hide yes)
			)
		)
		(property "License" "Apache-2.0"
			(at 109.22 49.53 0)
			(effects
				(font
					(size 1.27 1.27)
					(thickness 0.15)
				)
				(justify left bottom)
				(hide yes)
			)
		)
		(pin "1"
		)
		(instances
			(project "k410t-devboard"
				(path ""
					(reference "#PWR057")
					(unit 1)
				)
			)
		)
	)
	(symbol
		(lib_id "antmicroResistors0402:R_100R_0402")
		(at 218.44 104.14 180)
		(unit 1)
		(exclude_from_sim no)
		(in_bom yes)
		(on_board yes)
		(dnp no)
		(property "Reference" "R32"
			(at 220.345 102.87 0)
			(effects
				(font
					(size 1.27 1.27)
				)
			)
		)
		(property "Value" "R_100R_0402"
			(at 198.12 91.44 0)
			(effects
				(font
					(size 1.27 1.27)
					(thickness 0.15)
				)
				(justify left bottom)
				(hide yes)
			)
		)
		(property "Footprint" "antmicro-footprints:R_0402_1005Metric"
			(at 198.12 88.9 0)
			(effects
				(font
					(size 1.27 1.27)
					(thickness 0.15)
				)
				(justify left bottom)
				(hide yes)
			)
		)
		(property "Datasheet" "https://www.bourns.com/docs/product-datasheets/cr.pdf"
			(at 198.12 86.36 0)
			(effects
				(font
					(size 1.27 1.27)
					(thickness 0.15)
				)
				(justify left bottom)
				(hide yes)
			)
		)
		(property "Description" ""
			(at 218.44 104.14 0)
			(effects
				(font
					(size 1.27 1.27)
				)
			)
		)
		(property "Manufacturer" "Bourns"
			(at 198.12 81.28 0)
			(effects
				(font
					(size 1.27 1.27)
					(thickness 0.15)
				)
				(justify left bottom)
				(hide yes)
			)
		)
		(property "MPN" "CR0402-FX-1000GLF"
			(at 198.12 83.82 0)
			(effects
				(font
					(size 1.27 1.27)
					(thickness 0.15)
				)
				(justify left bottom)
				(hide yes)
			)
		)
		(property "Val" "100R"
			(at 210.82 102.87 0)
			(effects
				(font
					(size 1.27 1.27)
					(thickness 0.15)
				)
			)
		)
		(property "License" "Apache-2.0"
			(at 198.12 78.74 0)
			(effects
				(font
					(size 1.27 1.27)
					(thickness 0.15)
				)
				(justify left bottom)
				(hide yes)
			)
		)
		(property "Author" "Antmicro"
			(at 198.12 76.2 0)
			(effects
				(font
					(size 1.27 1.27)
					(thickness 0.15)
				)
				(justify left bottom)
				(hide yes)
			)
		)
		(property "Tolerance" "1%"
			(at 198.12 93.98 0)
			(effects
				(font
					(size 1.27 1.27)
				)
				(justify left bottom)
				(hide yes)
			)
		)
		(pin "1"
		)
		(pin "2"
		)
		(instances
			(project "k410t-devboard"
				(path ""
					(reference "R32")
					(unit 1)
				)
			)
		)
	)
	(symbol
		(lib_id "antmicropower:GND")
		(at 152.4 35.56 0)
		(unit 1)
		(exclude_from_sim no)
		(in_bom yes)
		(on_board yes)
		(dnp no)
		(property "Reference" "#PWR063"
			(at 152.4 41.91 0)
			(effects
				(font
					(size 1.27 1.27)
				)
				(hide yes)
			)
		)
		(property "Value" "GND"
			(at 152.4 39.37 0)
			(effects
				(font
					(size 1.27 1.27)
				)
			)
		)
		(property "Footprint" ""
			(at 161.29 43.18 0)
			(effects
				(font
					(size 1.27 1.27)
					(thickness 0.15)
				)
				(justify left bottom)
				(hide yes)
			)
		)
		(property "Datasheet" ""
			(at 161.29 48.26 0)
			(effects
				(font
					(size 1.27 1.27)
					(thickness 0.15)
				)
				(justify left bottom)
				(hide yes)
			)
		)
		(property "Description" ""
			(at 152.4 35.56 0)
			(effects
				(font
					(size 1.27 1.27)
				)
			)
		)
		(property "Author" "Antmicro"
			(at 161.29 43.18 0)
			(effects
				(font
					(size 1.27 1.27)
					(thickness 0.15)
				)
				(justify left bottom)
				(hide yes)
			)
		)
		(property "License" "Apache-2.0"
			(at 161.29 45.72 0)
			(effects
				(font
					(size 1.27 1.27)
					(thickness 0.15)
				)
				(justify left bottom)
				(hide yes)
			)
		)
		(pin "1"
		)
		(instances
			(project "k410t-devboard"
				(path ""
					(reference "#PWR063")
					(unit 1)
				)
			)
		)
	)
	(symbol
		(lib_id "antmicropower:GND")
		(at 196.85 35.56 0)
		(unit 1)
		(exclude_from_sim no)
		(in_bom yes)
		(on_board yes)
		(dnp no)
		(property "Reference" "#PWR072"
			(at 196.85 41.91 0)
			(effects
				(font
					(size 1.27 1.27)
				)
				(hide yes)
			)
		)
		(property "Value" "GND"
			(at 196.85 39.37 0)
			(effects
				(font
					(size 1.27 1.27)
				)
			)
		)
		(property "Footprint" ""
			(at 205.74 43.18 0)
			(effects
				(font
					(size 1.27 1.27)
					(thickness 0.15)
				)
				(justify left bottom)
				(hide yes)
			)
		)
		(property "Datasheet" ""
			(at 205.74 48.26 0)
			(effects
				(font
					(size 1.27 1.27)
					(thickness 0.15)
				)
				(justify left bottom)
				(hide yes)
			)
		)
		(property "Description" ""
			(at 196.85 35.56 0)
			(effects
				(font
					(size 1.27 1.27)
				)
			)
		)
		(property "Author" "Antmicro"
			(at 205.74 43.18 0)
			(effects
				(font
					(size 1.27 1.27)
					(thickness 0.15)
				)
				(justify left bottom)
				(hide yes)
			)
		)
		(property "License" "Apache-2.0"
			(at 205.74 45.72 0)
			(effects
				(font
					(size 1.27 1.27)
					(thickness 0.15)
				)
				(justify left bottom)
				(hide yes)
			)
		)
		(pin "1"
		)
		(instances
			(project "k410t-devboard"
				(path ""
					(reference "#PWR072")
					(unit 1)
				)
			)
		)
	)
	(symbol
		(lib_id "antmicroResistorNetworksArrays:4x39R_0201_array")
		(at 308.61 104.14 0)
		(unit 1)
		(exclude_from_sim no)
		(in_bom yes)
		(on_board yes)
		(dnp no)
		(fields_autoplaced yes)
		(property "Reference" "R15"
			(at 313.69 115.57 0)
			(effects
				(font
					(size 1.27 1.27)
				)
			)
		)
		(property "Value" "4x39R_0201_array"
			(at 335.28 109.855 0)
			(effects
				(font
					(size 1.27 1.27)
					(thickness 0.15)
				)
				(justify left bottom)
				(hide yes)
			)
		)
		(property "Footprint" "antmicro-footprints:R_Array_4x0201_Panasonic_EXB18V"
			(at 335.28 114.935 0)
			(effects
				(font
					(size 1.27 1.27)
					(thickness 0.15)
				)
				(justify left bottom)
				(hide yes)
			)
		)
		(property "Datasheet" "https://eu.mouser.com/datasheet/2/315/AOC0000C14-1108062.pdf"
			(at 335.28 117.475 0)
			(effects
				(font
					(size 1.27 1.27)
					(thickness 0.15)
				)
				(justify left bottom)
				(hide yes)
			)
		)
		(property "Description" ""
			(at 308.61 104.14 0)
			(effects
				(font
					(size 1.27 1.27)
				)
			)
		)
		(property "MPN" "EXB-18V390JX"
			(at 335.28 120.015 0)
			(effects
				(font
					(size 1.27 1.27)
					(thickness 0.15)
				)
				(justify left bottom)
				(hide yes)
			)
		)
		(property "Manufacturer" "Panasonic"
			(at 335.28 122.555 0)
			(effects
				(font
					(size 1.27 1.27)
					(thickness 0.15)
				)
				(justify left bottom)
				(hide yes)
			)
		)
		(property "Author" "Antmicro"
			(at 335.28 125.095 0)
			(effects
				(font
					(size 1.27 1.27)
					(thickness 0.15)
				)
				(justify left bottom)
				(hide yes)
			)
		)
		(property "License" "Apache-2.0"
			(at 335.28 127.635 0)
			(effects
				(font
					(size 1.27 1.27)
					(thickness 0.15)
				)
				(justify left bottom)
				(hide yes)
			)
		)
		(property "Val" "4x39R_0201"
			(at 313.69 118.11 0)
			(effects
				(font
					(size 1.27 1.27)
				)
			)
		)
		(pin "1"
		)
		(pin "2"
		)
		(pin "3"
		)
		(pin "4"
		)
		(pin "5"
		)
		(pin "6"
		)
		(pin "7"
		)
		(pin "8"
		)
		(instances
			(project "k410t-devboard"
				(path ""
					(reference "R15")
					(unit 1)
				)
			)
		)
	)
	(symbol
		(lib_id "antmicropower:GND")
		(at 214.63 35.56 0)
		(unit 1)
		(exclude_from_sim no)
		(in_bom yes)
		(on_board yes)
		(dnp no)
		(property "Reference" "#PWR077"
			(at 214.63 41.91 0)
			(effects
				(font
					(size 1.27 1.27)
				)
				(hide yes)
			)
		)
		(property "Value" "GND"
			(at 214.63 39.37 0)
			(effects
				(font
					(size 1.27 1.27)
				)
			)
		)
		(property "Footprint" ""
			(at 223.52 43.18 0)
			(effects
				(font
					(size 1.27 1.27)
					(thickness 0.15)
				)
				(justify left bottom)
				(hide yes)
			)
		)
		(property "Datasheet" ""
			(at 223.52 48.26 0)
			(effects
				(font
					(size 1.27 1.27)
					(thickness 0.15)
				)
				(justify left bottom)
				(hide yes)
			)
		)
		(property "Description" ""
			(at 214.63 35.56 0)
			(effects
				(font
					(size 1.27 1.27)
				)
			)
		)
		(property "Author" "Antmicro"
			(at 223.52 43.18 0)
			(effects
				(font
					(size 1.27 1.27)
					(thickness 0.15)
				)
				(justify left bottom)
				(hide yes)
			)
		)
		(property "License" "Apache-2.0"
			(at 223.52 45.72 0)
			(effects
				(font
					(size 1.27 1.27)
					(thickness 0.15)
				)
				(justify left bottom)
				(hide yes)
			)
		)
		(pin "1"
		)
		(instances
			(project "k410t-devboard"
				(path ""
					(reference "#PWR077")
					(unit 1)
				)
			)
		)
	)
	(symbol
		(lib_id "antmicroCapacitors0402:C_100n_0402")
		(at 223.52 33.02 90)
		(unit 1)
		(exclude_from_sim no)
		(in_bom yes)
		(on_board yes)
		(dnp no)
		(property "Reference" "C295"
			(at 224.155 28.575 90)
			(effects
				(font
					(size 1.27 1.27)
				)
				(justify right)
			)
		)
		(property "Value" "C_100n_0402"
			(at 233.68 12.7 0)
			(effects
				(font
					(size 1.27 1.27)
					(thickness 0.15)
				)
				(justify left bottom)
				(hide yes)
			)
		)
		(property "Footprint" "antmicro-footprints:C_0402_1005Metric"
			(at 236.22 12.7 0)
			(effects
				(font
					(size 1.27 1.27)
					(thickness 0.15)
				)
				(justify left bottom)
				(hide yes)
			)
		)
		(property "Datasheet" "https://www.murata.com/products/productdetail?partno=GRM155R61H104KE14%23"
			(at 238.76 12.7 0)
			(effects
				(font
					(size 1.27 1.27)
					(thickness 0.15)
				)
				(justify left bottom)
				(hide yes)
			)
		)
		(property "Description" ""
			(at 223.52 33.02 0)
			(effects
				(font
					(size 1.27 1.27)
				)
			)
		)
		(property "Manufacturer" "Murata"
			(at 243.84 12.7 0)
			(effects
				(font
					(size 1.27 1.27)
					(thickness 0.15)
				)
				(justify left bottom)
				(hide yes)
			)
		)
		(property "MPN" "GRM155R61H104KE14D"
			(at 241.3 12.7 0)
			(effects
				(font
					(size 1.27 1.27)
					(thickness 0.15)
				)
				(justify left bottom)
				(hide yes)
			)
		)
		(property "Val" "100n"
			(at 224.155 32.385 90)
			(effects
				(font
					(size 1.27 1.27)
					(thickness 0.15)
				)
				(justify right)
			)
		)
		(property "License" "Apache-2.0"
			(at 246.38 12.7 0)
			(effects
				(font
					(size 1.27 1.27)
					(thickness 0.15)
				)
				(justify left bottom)
				(hide yes)
			)
		)
		(property "Author" "Antmicro"
			(at 248.92 12.7 0)
			(effects
				(font
					(size 1.27 1.27)
					(thickness 0.15)
				)
				(justify left bottom)
				(hide yes)
			)
		)
		(property "Voltage" "50V"
			(at 251.46 12.7 0)
			(effects
				(font
					(size 1.27 1.27)
				)
				(justify left bottom)
				(hide yes)
			)
		)
		(property "Dielectric" "X5R"
			(at 254 12.7 0)
			(effects
				(font
					(size 1.27 1.27)
				)
				(justify left bottom)
				(hide yes)
			)
		)
		(pin "1"
		)
		(pin "2"
		)
		(instances
			(project "k410t-devboard"
				(path ""
					(reference "C295")
					(unit 1)
				)
			)
		)
	)
	(symbol
		(lib_id "antmicroCapacitors0603:C_47u_0603")
		(at 311.15 50.8 90)
		(unit 1)
		(exclude_from_sim no)
		(in_bom yes)
		(on_board yes)
		(dnp no)
		(property "Reference" "C166"
			(at 311.785 46.355 90)
			(effects
				(font
					(size 1.27 1.27)
				)
				(justify right)
			)
		)
		(property "Value" "C_47u_0603"
			(at 321.31 30.48 0)
			(effects
				(font
					(size 1.27 1.27)
					(thickness 0.15)
				)
				(justify left bottom)
				(hide yes)
			)
		)
		(property "Footprint" "antmicro-footprints:C_0603_1608Metric"
			(at 323.85 30.48 0)
			(effects
				(font
					(size 1.27 1.27)
					(thickness 0.15)
				)
				(justify left bottom)
				(hide yes)
			)
		)
		(property "Datasheet" "https://www.murata.com/products/productdetail?partno=GRM188R60J476ME15%23"
			(at 326.39 30.48 0)
			(effects
				(font
					(size 1.27 1.27)
					(thickness 0.15)
				)
				(justify left bottom)
				(hide yes)
			)
		)
		(property "Description" ""
			(at 311.15 50.8 0)
			(effects
				(font
					(size 1.27 1.27)
				)
			)
		)
		(property "Manufacturer" "Murata"
			(at 331.47 30.48 0)
			(effects
				(font
					(size 1.27 1.27)
					(thickness 0.15)
				)
				(justify left bottom)
				(hide yes)
			)
		)
		(property "MPN" "GRM188R60J476ME15D"
			(at 328.93 30.48 0)
			(effects
				(font
					(size 1.27 1.27)
					(thickness 0.15)
				)
				(justify left bottom)
				(hide yes)
			)
		)
		(property "Val" "47u"
			(at 311.785 50.165 90)
			(effects
				(font
					(size 1.27 1.27)
					(thickness 0.15)
				)
				(justify right)
			)
		)
		(property "License" "Apache-2.0"
			(at 334.01 30.48 0)
			(effects
				(font
					(size 1.27 1.27)
					(thickness 0.15)
				)
				(justify left bottom)
				(hide yes)
			)
		)
		(property "Author" "Antmicro"
			(at 336.55 30.48 0)
			(effects
				(font
					(size 1.27 1.27)
					(thickness 0.15)
				)
				(justify left bottom)
				(hide yes)
			)
		)
		(property "Voltage" ""
			(at 339.09 30.48 0)
			(effects
				(font
					(size 1.27 1.27)
				)
				(justify left bottom)
				(hide yes)
			)
		)
		(property "Dielectric" ""
			(at 341.63 30.48 0)
			(effects
				(font
					(size 1.27 1.27)
				)
				(justify left bottom)
				(hide yes)
			)
		)
		(pin "1"
		)
		(pin "2"
		)
		(instances
			(project "k410t-devboard"
				(path ""
					(reference "C166")
					(unit 1)
				)
			)
		)
	)
	(symbol
		(lib_id "antmicroCapacitors0402:C_100n_0402")
		(at 342.9 59.69 90)
		(unit 1)
		(exclude_from_sim no)
		(in_bom yes)
		(on_board yes)
		(dnp no)
		(property "Reference" "C173"
			(at 343.535 55.245 90)
			(effects
				(font
					(size 1.27 1.27)
				)
				(justify right)
			)
		)
		(property "Value" "C_100n_0402"
			(at 353.06 39.37 0)
			(effects
				(font
					(size 1.27 1.27)
					(thickness 0.15)
				)
				(justify left bottom)
				(hide yes)
			)
		)
		(property "Footprint" "antmicro-footprints:C_0402_1005Metric"
			(at 355.6 39.37 0)
			(effects
				(font
					(size 1.27 1.27)
					(thickness 0.15)
				)
				(justify left bottom)
				(hide yes)
			)
		)
		(property "Datasheet" "https://www.murata.com/products/productdetail?partno=GRM155R61H104KE14%23"
			(at 358.14 39.37 0)
			(effects
				(font
					(size 1.27 1.27)
					(thickness 0.15)
				)
				(justify left bottom)
				(hide yes)
			)
		)
		(property "Description" ""
			(at 342.9 59.69 0)
			(effects
				(font
					(size 1.27 1.27)
				)
			)
		)
		(property "Manufacturer" "Murata"
			(at 363.22 39.37 0)
			(effects
				(font
					(size 1.27 1.27)
					(thickness 0.15)
				)
				(justify left bottom)
				(hide yes)
			)
		)
		(property "MPN" "GRM155R61H104KE14D"
			(at 360.68 39.37 0)
			(effects
				(font
					(size 1.27 1.27)
					(thickness 0.15)
				)
				(justify left bottom)
				(hide yes)
			)
		)
		(property "Val" "100n"
			(at 343.535 59.055 90)
			(effects
				(font
					(size 1.27 1.27)
					(thickness 0.15)
				)
				(justify right)
			)
		)
		(property "License" "Apache-2.0"
			(at 365.76 39.37 0)
			(effects
				(font
					(size 1.27 1.27)
					(thickness 0.15)
				)
				(justify left bottom)
				(hide yes)
			)
		)
		(property "Author" "Antmicro"
			(at 368.3 39.37 0)
			(effects
				(font
					(size 1.27 1.27)
					(thickness 0.15)
				)
				(justify left bottom)
				(hide yes)
			)
		)
		(property "Voltage" "50V"
			(at 370.84 39.37 0)
			(effects
				(font
					(size 1.27 1.27)
				)
				(justify left bottom)
				(hide yes)
			)
		)
		(property "Dielectric" "X5R"
			(at 373.38 39.37 0)
			(effects
				(font
					(size 1.27 1.27)
				)
				(justify left bottom)
				(hide yes)
			)
		)
		(pin "1"
		)
		(pin "2"
		)
		(instances
			(project "k410t-devboard"
				(path ""
					(reference "C173")
					(unit 1)
				)
			)
		)
	)
	(symbol
		(lib_id "antmicropower:+3.3V")
		(at 173.99 182.88 0)
		(unit 1)
		(exclude_from_sim no)
		(in_bom yes)
		(on_board yes)
		(dnp no)
		(fields_autoplaced yes)
		(property "Reference" "#PWR073"
			(at 173.99 186.69 0)
			(effects
				(font
					(size 1.27 1.27)
				)
				(hide yes)
			)
		)
		(property "Value" "+3V3"
			(at 173.99 179.324 0)
			(effects
				(font
					(size 1.27 1.27)
				)
			)
		)
		(property "Footprint" ""
			(at 173.99 182.88 0)
			(effects
				(font
					(size 1.27 1.27)
				)
				(hide yes)
			)
		)
		(property "Datasheet" ""
			(at 173.99 182.88 0)
			(effects
				(font
					(size 1.27 1.27)
				)
				(hide yes)
			)
		)
		(property "Description" ""
			(at 173.99 182.88 0)
			(effects
				(font
					(size 1.27 1.27)
				)
			)
		)
		(pin "1"
		)
		(instances
			(project "k410t-devboard"
				(path ""
					(reference "#PWR073")
					(unit 1)
				)
			)
		)
	)
	(symbol
		(lib_id "antmicropower:GND")
		(at 140.97 250.19 0)
		(unit 1)
		(exclude_from_sim no)
		(in_bom yes)
		(on_board yes)
		(dnp no)
		(property "Reference" "#PWR059"
			(at 140.97 256.54 0)
			(effects
				(font
					(size 1.27 1.27)
				)
				(hide yes)
			)
		)
		(property "Value" "GND"
			(at 140.97 254 0)
			(effects
				(font
					(size 1.27 1.27)
				)
			)
		)
		(property "Footprint" ""
			(at 149.86 257.81 0)
			(effects
				(font
					(size 1.27 1.27)
					(thickness 0.15)
				)
				(justify left bottom)
				(hide yes)
			)
		)
		(property "Datasheet" ""
			(at 149.86 262.89 0)
			(effects
				(font
					(size 1.27 1.27)
					(thickness 0.15)
				)
				(justify left bottom)
				(hide yes)
			)
		)
		(property "Description" ""
			(at 140.97 250.19 0)
			(effects
				(font
					(size 1.27 1.27)
				)
			)
		)
		(property "Author" "Antmicro"
			(at 149.86 257.81 0)
			(effects
				(font
					(size 1.27 1.27)
					(thickness 0.15)
				)
				(justify left bottom)
				(hide yes)
			)
		)
		(property "License" "Apache-2.0"
			(at 149.86 260.35 0)
			(effects
				(font
					(size 1.27 1.27)
					(thickness 0.15)
				)
				(justify left bottom)
				(hide yes)
			)
		)
		(pin "1"
		)
		(instances
			(project "k410t-devboard"
				(path ""
					(reference "#PWR059")
					(unit 1)
				)
			)
		)
	)
	(symbol
		(lib_id "antmicroCapacitors0402:C_10u_0402")
		(at 266.7 33.02 90)
		(unit 1)
		(exclude_from_sim no)
		(in_bom yes)
		(on_board yes)
		(dnp no)
		(property "Reference" "C188"
			(at 267.335 28.575 90)
			(effects
				(font
					(size 1.27 1.27)
				)
				(justify right)
			)
		)
		(property "Value" "C_10u_0402"
			(at 276.86 12.7 0)
			(effects
				(font
					(size 1.27 1.27)
					(thickness 0.15)
				)
				(justify left bottom)
				(hide yes)
			)
		)
		(property "Footprint" "antmicro-footprints:C_0402_1005Metric"
			(at 279.4 12.7 0)
			(effects
				(font
					(size 1.27 1.27)
					(thickness 0.15)
				)
				(justify left bottom)
				(hide yes)
			)
		)
		(property "Datasheet" "https://www.yageo.com/en/Chart/Download/pdf/CC0402MRX5R5BB106"
			(at 281.94 12.7 0)
			(effects
				(font
					(size 1.27 1.27)
					(thickness 0.15)
				)
				(justify left bottom)
				(hide yes)
			)
		)
		(property "Description" ""
			(at 266.7 33.02 0)
			(effects
				(font
					(size 1.27 1.27)
				)
			)
		)
		(property "Manufacturer" "YAGEO"
			(at 287.02 12.7 0)
			(effects
				(font
					(size 1.27 1.27)
					(thickness 0.15)
				)
				(justify left bottom)
				(hide yes)
			)
		)
		(property "MPN" "CC0402MRX5R5BB106"
			(at 284.48 12.7 0)
			(effects
				(font
					(size 1.27 1.27)
					(thickness 0.15)
				)
				(justify left bottom)
				(hide yes)
			)
		)
		(property "Val" "10u"
			(at 267.335 32.385 90)
			(effects
				(font
					(size 1.27 1.27)
					(thickness 0.15)
				)
				(justify right)
			)
		)
		(property "License" "Apache-2.0"
			(at 289.56 12.7 0)
			(effects
				(font
					(size 1.27 1.27)
					(thickness 0.15)
				)
				(justify left bottom)
				(hide yes)
			)
		)
		(property "Author" "Antmicro"
			(at 292.1 12.7 0)
			(effects
				(font
					(size 1.27 1.27)
					(thickness 0.15)
				)
				(justify left bottom)
				(hide yes)
			)
		)
		(property "Voltage" ""
			(at 294.64 12.7 0)
			(effects
				(font
					(size 1.27 1.27)
				)
				(justify left bottom)
				(hide yes)
			)
		)
		(property "Dielectric" ""
			(at 297.18 12.7 0)
			(effects
				(font
					(size 1.27 1.27)
				)
				(justify left bottom)
				(hide yes)
			)
		)
		(pin "1"
		)
		(pin "2"
		)
		(instances
			(project "k410t-devboard"
				(path ""
					(reference "C188")
					(unit 1)
				)
			)
		)
	)
	(symbol
		(lib_id "antmicropower:GND")
		(at 147.32 114.3 0)
		(unit 1)
		(exclude_from_sim no)
		(in_bom yes)
		(on_board yes)
		(dnp no)
		(property "Reference" "#PWR062"
			(at 147.32 120.65 0)
			(effects
				(font
					(size 1.27 1.27)
				)
				(hide yes)
			)
		)
		(property "Value" "GND"
			(at 147.32 118.11 0)
			(effects
				(font
					(size 1.27 1.27)
				)
			)
		)
		(property "Footprint" ""
			(at 156.21 121.92 0)
			(effects
				(font
					(size 1.27 1.27)
					(thickness 0.15)
				)
				(justify left bottom)
				(hide yes)
			)
		)
		(property "Datasheet" ""
			(at 156.21 127 0)
			(effects
				(font
					(size 1.27 1.27)
					(thickness 0.15)
				)
				(justify left bottom)
				(hide yes)
			)
		)
		(property "Description" ""
			(at 147.32 114.3 0)
			(effects
				(font
					(size 1.27 1.27)
				)
			)
		)
		(property "Author" "Antmicro"
			(at 156.21 121.92 0)
			(effects
				(font
					(size 1.27 1.27)
					(thickness 0.15)
				)
				(justify left bottom)
				(hide yes)
			)
		)
		(property "License" "Apache-2.0"
			(at 156.21 124.46 0)
			(effects
				(font
					(size 1.27 1.27)
					(thickness 0.15)
				)
				(justify left bottom)
				(hide yes)
			)
		)
		(pin "1"
		)
		(instances
			(project "k410t-devboard"
				(path ""
					(reference "#PWR062")
					(unit 1)
				)
			)
		)
	)
	(symbol
		(lib_id "antmicropower:GND")
		(at 196.85 63.5 0)
		(unit 1)
		(exclude_from_sim no)
		(in_bom yes)
		(on_board yes)
		(dnp no)
		(property "Reference" "#PWR074"
			(at 196.85 69.85 0)
			(effects
				(font
					(size 1.27 1.27)
				)
				(hide yes)
			)
		)
		(property "Value" "GND"
			(at 196.85 67.31 0)
			(effects
				(font
					(size 1.27 1.27)
				)
			)
		)
		(property "Footprint" ""
			(at 205.74 71.12 0)
			(effects
				(font
					(size 1.27 1.27)
					(thickness 0.15)
				)
				(justify left bottom)
				(hide yes)
			)
		)
		(property "Datasheet" ""
			(at 205.74 76.2 0)
			(effects
				(font
					(size 1.27 1.27)
					(thickness 0.15)
				)
				(justify left bottom)
				(hide yes)
			)
		)
		(property "Description" ""
			(at 196.85 63.5 0)
			(effects
				(font
					(size 1.27 1.27)
				)
			)
		)
		(property "Author" "Antmicro"
			(at 205.74 71.12 0)
			(effects
				(font
					(size 1.27 1.27)
					(thickness 0.15)
				)
				(justify left bottom)
				(hide yes)
			)
		)
		(property "License" "Apache-2.0"
			(at 205.74 73.66 0)
			(effects
				(font
					(size 1.27 1.27)
					(thickness 0.15)
				)
				(justify left bottom)
				(hide yes)
			)
		)
		(pin "1"
		)
		(instances
			(project "k410t-devboard"
				(path ""
					(reference "#PWR074")
					(unit 1)
				)
			)
		)
	)
	(symbol
		(lib_id "antmicroCapacitors0402:C_100n_0402")
		(at 334.01 50.8 90)
		(unit 1)
		(exclude_from_sim no)
		(in_bom yes)
		(on_board yes)
		(dnp no)
		(property "Reference" "C170"
			(at 334.645 46.355 90)
			(effects
				(font
					(size 1.27 1.27)
				)
				(justify right)
			)
		)
		(property "Value" "C_100n_0402"
			(at 344.17 30.48 0)
			(effects
				(font
					(size 1.27 1.27)
					(thickness 0.15)
				)
				(justify left bottom)
				(hide yes)
			)
		)
		(property "Footprint" "antmicro-footprints:C_0402_1005Metric"
			(at 346.71 30.48 0)
			(effects
				(font
					(size 1.27 1.27)
					(thickness 0.15)
				)
				(justify left bottom)
				(hide yes)
			)
		)
		(property "Datasheet" "https://www.murata.com/products/productdetail?partno=GRM155R61H104KE14%23"
			(at 349.25 30.48 0)
			(effects
				(font
					(size 1.27 1.27)
					(thickness 0.15)
				)
				(justify left bottom)
				(hide yes)
			)
		)
		(property "Description" ""
			(at 334.01 50.8 0)
			(effects
				(font
					(size 1.27 1.27)
				)
			)
		)
		(property "Manufacturer" "Murata"
			(at 354.33 30.48 0)
			(effects
				(font
					(size 1.27 1.27)
					(thickness 0.15)
				)
				(justify left bottom)
				(hide yes)
			)
		)
		(property "MPN" "GRM155R61H104KE14D"
			(at 351.79 30.48 0)
			(effects
				(font
					(size 1.27 1.27)
					(thickness 0.15)
				)
				(justify left bottom)
				(hide yes)
			)
		)
		(property "Val" "100n"
			(at 334.645 50.165 90)
			(effects
				(font
					(size 1.27 1.27)
					(thickness 0.15)
				)
				(justify right)
			)
		)
		(property "License" "Apache-2.0"
			(at 356.87 30.48 0)
			(effects
				(font
					(size 1.27 1.27)
					(thickness 0.15)
				)
				(justify left bottom)
				(hide yes)
			)
		)
		(property "Author" "Antmicro"
			(at 359.41 30.48 0)
			(effects
				(font
					(size 1.27 1.27)
					(thickness 0.15)
				)
				(justify left bottom)
				(hide yes)
			)
		)
		(property "Voltage" "50V"
			(at 361.95 30.48 0)
			(effects
				(font
					(size 1.27 1.27)
				)
				(justify left bottom)
				(hide yes)
			)
		)
		(property "Dielectric" "X5R"
			(at 364.49 30.48 0)
			(effects
				(font
					(size 1.27 1.27)
				)
				(justify left bottom)
				(hide yes)
			)
		)
		(pin "1"
		)
		(pin "2"
		)
		(instances
			(project "k410t-devboard"
				(path ""
					(reference "C170")
					(unit 1)
				)
			)
		)
	)
)
